G04 ================== begin FILE IDENTIFICATION RECORD ==================*
G04 Layout Name:  9049_F0T_FAN_BOARD_MP5048_D_v02_20221209_0830.brd*
G04 Film Name:    smb.art*
G04 File Format:  Gerber RS274X*
G04 File Origin:  Cadence Allegro 17.2-S081*
G04 Origin Date:  Mon Dec 12 15:05:04 2022*
G04 *
G04 Layer:  DRAWING FORMAT/TITLE_BLOCK_A*
G04 Layer:  DRAWING FORMAT/TITLE_BLOCK*
G04 Layer:  VIA CLASS/SOLDERMASK_BOTTOM*
G04 Layer:  PIN/SOLDERMASK_BOTTOM*
G04 Layer:  PACKAGE GEOMETRY/SOLDERMASK_BOTTOM*
G04 Layer:  MANUFACTURING/PHOTOPLOT_OUTLINE*
G04 Layer:  DRAWING FORMAT/TITLE_DATA_SMB*
G04 Layer:  BOARD GEOMETRY/SOLDERMASK_BOTTOM*
G04 *
G04 Offset:    (0.00 0.00)*
G04 Mirror:    No*
G04 Mode:      Positive*
G04 Rotation:  0*
G04 FullContactRelief:  No*
G04 UndefLineWidth:     6.00*
G04 ================== end FILE IDENTIFICATION RECORD ====================*
%FSLAX25Y25*MOIN*%
%IR0*IPPOS*OFA0.00000B0.00000*MIA0B0*SFA1.00000B1.00000*%
%ADD25R,.103X.016*%
%ADD46R,.036X.201*%
%ADD11C,.03*%
%AMMACRO42*
4,1,5,-.04924,-.00791,
.04217,-.00791,
.04924,-.00083,
.04924,.00791,
-.04924,.00791,
-.04924,-.00791,
0.0*
%
%ADD42MACRO42*%
%ADD47O,.398X1.264*%
%ADD36R,.134X.099*%
%ADD15C,.058*%
%ADD10C,.085*%
%ADD14C,.079*%
%ADD16R,.058X.058*%
%AMMACRO33*
4,1,28,-.00589,.01192,
-.006913,.011842,
-.007907,.011587,
-.008842,.011163,
-.009688,.010584,
-.010422,.009866,
-.011019,.009032,
-.011463,.008107,
-.011739,.007119,
-.01184,.006097,
-.01184,.00603,
-.01184,-.00148,
-.00948,-.00148,
-.00948,-.01191,
.00948,-.01191,
.00948,-.00148,
.01184,-.00148,
.01184,.00603,
.011751,.007052,
.011486,.008044,
.011053,.008974,
.010465,.009815,
.00974,.010541,
.0089,.01113,
.00797,.011564,
.006979,.01183,
.005957,.01192,
.00589,.01192,
-.00589,.01192,
0.0*
%
%ADD33MACRO33*%
%AMMACRO35*
4,1,28,.01192,.00589,
.011842,.006913,
.011587,.007907,
.011163,.008842,
.010584,.009688,
.009866,.010422,
.009032,.011019,
.008107,.011463,
.007119,.011739,
.006097,.01184,
.00603,.01184,
-.00148,.01184,
-.00148,.00948,
-.01191,.00948,
-.01191,-.00948,
-.00148,-.00948,
-.00148,-.01184,
.00603,-.01184,
.007052,-.011751,
.008044,-.011486,
.008974,-.011053,
.009815,-.010465,
.010541,-.00974,
.01113,-.0089,
.011564,-.00797,
.01183,-.006979,
.01192,-.005957,
.01192,-.00589,
.01192,.00589,
0.0*
%
%ADD35MACRO35*%
%AMMACRO32*
4,1,28,.0059,-.01191,
.006923,-.01183,
.007916,-.011573,
.00885,-.011148,
.009696,-.010567,
.010428,-.009849,
.011024,-.009013,
.011466,-.008088,
.011741,-.007099,
.01184,-.006078,
.01184,-.00602,
.01184,.00149,
.00948,.00149,
.00948,.01192,
-.00948,.01192,
-.00948,.00149,
-.01184,.00149,
-.01184,-.00602,
-.011751,-.007042,
-.011486,-.008033,
-.011053,-.008964,
-.010465,-.009805,
-.00974,-.010531,
-.0089,-.01112,
-.007971,-.011554,
-.00698,-.01182,
-.005958,-.01191,
-.0059,-.01191,
.0059,-.01191,
0.0*
%
%ADD32MACRO32*%
%AMMACRO34*
4,1,28,-.01191,-.0059,
-.01183,-.006923,
-.011573,-.007916,
-.011148,-.00885,
-.010567,-.009696,
-.009849,-.010428,
-.009013,-.011024,
-.008088,-.011466,
-.007099,-.011741,
-.006078,-.01184,
-.00602,-.01184,
.00149,-.01184,
.00149,-.00948,
.01192,-.00948,
.01192,.00948,
.00149,.00948,
.00149,.01184,
-.00602,.01184,
-.007042,.011751,
-.008033,.011486,
-.008964,.011053,
-.009805,.010465,
-.010531,.00974,
-.01112,.0089,
-.011554,.007971,
-.01182,.00698,
-.01191,.005958,
-.01191,.0059,
-.01191,-.0059,
0.0*
%
%ADD34MACRO34*%
%AMMACRO23*
4,1,6,.01578,-.01972,
.01578,-.00784,
-.0039,-.00784,
-.0039,.01972,
-.01578,.01972,
-.01578,-.01972,
.01578,-.01972,
0.0*
%
%ADD23MACRO23*%
%AMMACRO24*
4,1,6,.01578,-.01972,
.01578,.01972,
.0039,.01972,
.0039,-.00784,
-.01578,-.00784,
-.01578,-.01972,
.01578,-.01972,
0.0*
%
%ADD24MACRO24*%
%ADD37R,.134X.103*%
%ADD21R,.011X.04*%
%ADD17R,.103X.134*%
%ADD43R,.024X.022*%
%ADD44R,.022X.024*%
%ADD28R,.02X.028*%
%ADD27R,.05X.017*%
%ADD39R,.036X.032*%
%ADD49R,.032X.036*%
%ADD41R,.054X.044*%
%ADD19R,.044X.054*%
%ADD18R,.05X.066*%
%ADD45C,.118*%
%ADD40C,.145*%
%ADD48R,.177X.252*%
%ADD29R,.028X.028*%
%AMMACRO26*
4,1,5,.04924,.00791,
-.04217,.00791,
-.04924,.00083,
-.04924,-.00791,
.04924,-.00791,
.04924,.00791,
0.0*
%
%ADD26MACRO26*%
%ADD38O,.359X.831*%
%AMMACRO31*
4,1,28,-.01192,-.00589,
-.011842,-.006913,
-.011587,-.007907,
-.011163,-.008842,
-.010584,-.009688,
-.009866,-.010422,
-.009032,-.011019,
-.008107,-.011463,
-.007119,-.011739,
-.006097,-.01184,
-.00603,-.01184,
.00148,-.01184,
.00148,-.00948,
.01191,-.00948,
.01191,.00948,
.00148,.00948,
.00148,.01184,
-.00603,.01184,
-.007052,.011751,
-.008044,.011486,
-.008974,.011053,
-.009815,.010465,
-.010541,.00974,
-.01113,.0089,
-.011564,.00797,
-.01183,.006979,
-.01192,.005957,
-.01192,.00589,
-.01192,-.00589,
0.0*
%
%ADD31MACRO31*%
%AMMACRO13*
4,1,28,.00589,-.01192,
.006913,-.011842,
.007907,-.011587,
.008842,-.011163,
.009688,-.010584,
.010422,-.009866,
.011019,-.009032,
.011463,-.008107,
.011739,-.007119,
.01184,-.006097,
.01184,-.00603,
.01184,.00148,
.00948,.00148,
.00948,.01191,
-.00948,.01191,
-.00948,.00148,
-.01184,.00148,
-.01184,-.00603,
-.011751,-.007052,
-.011486,-.008044,
-.011053,-.008974,
-.010465,-.009815,
-.00974,-.010541,
-.0089,-.01113,
-.00797,-.011564,
-.006979,-.01183,
-.005957,-.01192,
-.00589,-.01192,
.00589,-.01192,
0.0*
%
%ADD13MACRO13*%
%AMMACRO30*
4,1,28,.01191,.0059,
.01183,.006923,
.011573,.007916,
.011148,.00885,
.010567,.009696,
.009849,.010428,
.009013,.011024,
.008088,.011466,
.007099,.011741,
.006078,.01184,
.00602,.01184,
-.00149,.01184,
-.00149,.00948,
-.01192,.00948,
-.01192,-.00948,
-.00149,-.00948,
-.00149,-.01184,
.00602,-.01184,
.007042,-.011751,
.008033,-.011486,
.008964,-.011053,
.009805,-.010465,
.010531,-.00974,
.01112,-.0089,
.011554,-.007971,
.01182,-.00698,
.01191,-.005958,
.01191,-.0059,
.01191,.0059,
0.0*
%
%ADD30MACRO30*%
%AMMACRO20*
4,1,6,-.01578,.01972,
-.01578,.00784,
.0039,.00784,
.0039,-.01972,
.01578,-.01972,
.01578,.01972,
-.01578,.01972,
0.0*
%
%ADD20MACRO20*%
%AMMACRO12*
4,1,28,-.0059,.01191,
-.006923,.01183,
-.007916,.011573,
-.00885,.011148,
-.009696,.010567,
-.010428,.009849,
-.011024,.009013,
-.011466,.008088,
-.011741,.007099,
-.01184,.006078,
-.01184,.00602,
-.01184,-.00149,
-.00948,-.00149,
-.00948,-.01192,
.00948,-.01192,
.00948,-.00149,
.01184,-.00149,
.01184,.00602,
.011751,.007042,
.011486,.008033,
.011053,.008964,
.010465,.009805,
.00974,.010531,
.0089,.01112,
.007971,.011554,
.00698,.01182,
.005958,.01191,
.0059,.01191,
-.0059,.01191,
0.0*
%
%ADD12MACRO12*%
%AMMACRO22*
4,1,6,-.01578,.01972,
-.01578,-.01972,
-.0039,-.01972,
-.0039,.00784,
.01578,.00784,
.01578,.01972,
-.01578,.01972,
0.0*
%
%ADD22MACRO22*%
%ADD50C,.02*%
%ADD51C,.006*%
G75*
%LPD*%
G75*
G36*
G01X105394Y27176D02*
Y7283D01*
X99489Y1378D01*
X80158D01*
X74252Y7283D01*
Y27176D01*
X105394D01*
G37*
G36*
G01X68900Y1237000D02*
G03I-5900J0D01*
G37*
G36*
G01X123386Y1378D02*
X129292Y7283D01*
Y32285D01*
X107922D01*
Y7085D01*
X108348D01*
X114055Y1378D01*
X123386D01*
G37*
G36*
G01X125900Y267500D02*
G03I-5900J0D01*
G37*
G36*
G01X193800Y675200D02*
G03I-5900J0D01*
G37*
G54D10*
X-58431Y824000D03*
X-63431Y837184D03*
Y1152816D03*
X-58431Y1166000D03*
X-53431Y837184D03*
Y1152816D03*
X-27318Y824000D03*
X-32318Y837184D03*
X-22318D03*
X-32318Y1152816D03*
X-22318D03*
X-27318Y1166000D03*
G54D20*
X13584Y223012D03*
Y949784D03*
X46478Y304940D03*
X46978Y1031712D03*
X137275Y223012D03*
Y952933D03*
X155775Y304940D03*
Y1031712D03*
G54D11*
X10291Y249166D03*
X7240Y271043D03*
X12000Y641000D03*
X8612Y967317D03*
X8659Y974808D03*
X12047Y1003400D03*
X20650Y248510D03*
X31657Y249042D03*
X27185Y286228D03*
X18185D03*
X20452Y513547D03*
X27580Y528341D03*
X30380Y648320D03*
X32720Y660000D03*
X12389Y653509D03*
X25023Y663850D03*
Y669850D03*
X32728Y679000D03*
X12500D03*
X14925Y669000D03*
Y690000D03*
X20327Y711174D03*
X13375Y730274D03*
X15012Y745563D03*
X17458Y737184D03*
X13500Y862500D03*
X22630Y975714D03*
X31791Y975500D03*
X19500Y1239500D03*
X47487Y174264D03*
X38383Y280119D03*
X47561Y297728D03*
X40000Y334700D03*
X56925Y503000D03*
Y528500D03*
Y508500D03*
Y523500D03*
Y518500D03*
X57000Y538500D03*
X47499Y649000D03*
X52977Y662650D03*
X56475Y654000D03*
X46950Y666500D03*
X45240Y657000D03*
X56475Y672500D03*
X46950D03*
X52977Y681650D03*
X45240Y682000D03*
X57260Y1024020D03*
X48660Y1025650D03*
X68416Y63842D03*
X61000Y84192D03*
X61300Y66900D03*
X69100Y76100D03*
X75173Y78000D03*
X68500Y70000D03*
X71650Y94259D03*
Y111259D03*
X64025Y92575D03*
X65350Y102000D03*
X71500Y130000D03*
X62716Y129542D03*
X66000Y216800D03*
X80500Y273420D03*
X58561Y280728D03*
X74350Y276685D03*
X70000Y298500D03*
X61420Y299310D03*
X68700Y400000D03*
X78500Y406000D03*
X65900Y413000D03*
X69018Y420378D03*
X67000Y430500D03*
X71000Y427000D03*
X60773Y443728D03*
X74979Y437559D03*
X79500Y449925D03*
X65350Y447500D03*
X70500Y443500D03*
X65250Y470378D03*
X74500Y475000D03*
X68000Y463878D03*
X79293Y523513D03*
X75650Y517770D03*
X68345Y533265D03*
X73500Y562200D03*
X63070Y652400D03*
X68000Y664000D03*
X69000Y669745D03*
X68000Y676500D03*
X59475Y688975D03*
X60000Y696984D03*
X69350Y711940D03*
X68100Y721000D03*
X74075Y732000D03*
X65570Y734500D03*
X58612Y740500D03*
X69340Y758500D03*
X66000Y776000D03*
X61576Y762200D03*
X77816Y764764D03*
X78000Y782500D03*
X68481Y800951D03*
X69018Y783764D03*
X62058Y801075D03*
X67993Y827764D03*
X65350Y818654D03*
X71410Y846500D03*
X64500Y943500D03*
X80000Y980649D03*
X59268Y1007793D03*
X74800Y1003457D03*
X62500Y1025500D03*
X71210Y1024290D03*
X68686Y1139993D03*
X64425Y1165500D03*
X64843Y1194000D03*
X74313Y1178559D03*
X64850Y1179000D03*
X99000Y61000D03*
X87500Y83300D03*
X86000Y92000D03*
X94430Y103830D03*
X88900Y119300D03*
X82500Y389500D03*
X84500Y404000D03*
X82500Y398000D03*
X100835Y446500D03*
X91059Y452760D03*
X91593Y439000D03*
X95000Y462740D03*
X85500Y472975D03*
X86500Y481500D03*
X96502Y501930D03*
X95184Y493787D03*
X98040Y506730D03*
X87500Y522800D03*
X96275Y519750D03*
X84723Y532202D03*
X100505Y561919D03*
X97000Y569153D03*
X90680Y561766D03*
X98780Y617000D03*
X99051Y635051D03*
X87500Y634700D03*
X88300Y639800D03*
X83300Y624100D03*
X103037Y624462D03*
X95032Y660000D03*
X86000Y680000D03*
Y688000D03*
X101309Y675500D03*
X93025Y738000D03*
X99500Y787000D03*
X83000Y804000D03*
X94000Y825740D03*
X83000Y810000D03*
X82000Y833575D03*
X104500Y834500D03*
X115918Y75650D03*
X123500Y115500D03*
X123450Y238523D03*
X127482Y286228D03*
X107000Y389500D03*
X107966Y408260D03*
X112441Y418434D03*
X106850Y441596D03*
X125200Y453800D03*
X113500Y476000D03*
X118490Y495330D03*
X126070Y493931D03*
X112070Y499790D03*
X109000Y485000D03*
X111000Y506000D03*
X115788Y573787D03*
X106977Y561919D03*
X121500Y557500D03*
X114000Y591000D03*
X120000Y581500D03*
X108601Y627084D03*
X118079Y639954D03*
X124499Y660000D03*
X126185Y688915D03*
X123401Y669102D03*
X117500Y689900D03*
X126500Y706500D03*
X119000Y734000D03*
X125075Y715000D03*
X125352Y749277D03*
X114857Y741500D03*
X119836Y761664D03*
X107500Y782530D03*
X125654Y772281D03*
X107365Y776004D03*
X118711Y797500D03*
X125500Y820114D03*
X126000Y834500D03*
X117500Y857575D03*
X126500Y1129000D03*
X109500Y1139500D03*
X135500Y70441D03*
X142000Y74575D03*
X142500Y103342D03*
X138650Y94000D03*
X132500Y99000D03*
X135000Y120500D03*
X137449Y113340D03*
X135750Y132750D03*
X133982Y249166D03*
X140870Y249090D03*
X146133Y248610D03*
X144482Y265728D03*
X147500Y278228D03*
X136482Y286228D03*
X150270Y298590D03*
X135245Y407228D03*
X130500Y432500D03*
X139150Y420193D03*
Y429650D03*
X135349Y468652D03*
X135000Y463000D03*
X129000Y468000D03*
X150575Y504500D03*
X144324Y498325D03*
X145193Y504232D03*
X144335Y509166D03*
X138532Y507500D03*
X150575Y534500D03*
X131500Y634500D03*
X150300Y645900D03*
X141900Y645410D03*
X134575Y659000D03*
X128000Y694500D03*
X133575Y692000D03*
X136500Y728500D03*
X128065Y725566D03*
X146000Y729000D03*
X127983Y736234D03*
X133900Y776000D03*
X132350Y793241D03*
X139650Y785905D03*
X139075Y801984D03*
X141327Y822814D03*
X134525Y815114D03*
X134800Y826614D03*
X146505Y978795D03*
X133982Y979087D03*
X147229Y1004299D03*
X144482Y995649D03*
X128700Y999692D03*
X132175Y1117325D03*
X135800Y1138000D03*
X138650Y1149500D03*
X142500Y1161500D03*
X138650Y1165500D03*
X136800Y1194800D03*
X161100Y216500D03*
X155482Y248728D03*
X165014Y268287D03*
X167858Y279310D03*
X157103Y297803D03*
X170358Y298858D03*
X158858Y332228D03*
X153725Y524500D03*
Y514500D03*
X167190Y529510D03*
X171977Y656850D03*
X166547Y663500D03*
X159051Y671661D03*
X167679Y674254D03*
X167642Y682217D03*
X167060Y692500D03*
X171440Y708767D03*
X156962Y692037D03*
X171586Y735683D03*
X171580Y716500D03*
X171500Y743500D03*
X157000Y979000D03*
X164600Y998649D03*
X167858Y1007500D03*
X156858Y1024500D03*
X166207Y1025077D03*
X165500Y1229900D03*
X183600Y276685D03*
X179000Y298500D03*
X189800Y380300D03*
X188516Y518310D03*
X191991Y536336D03*
X191259Y547500D03*
X182500Y641600D03*
X187050Y652000D03*
Y663500D03*
X177500Y679500D03*
X175475Y668500D03*
X181475Y713000D03*
X193475Y706000D03*
X179000Y694000D03*
X190300Y725200D03*
X192582Y733000D03*
X181475Y747000D03*
X183600Y1005700D03*
X178358Y1024062D03*
X186458Y1106662D03*
X192000Y1240500D03*
X182600Y1228850D03*
G54D12*
X7000Y256712D03*
X6500Y983484D03*
X19000Y256748D03*
X15000D03*
X30000D03*
X18500Y983484D03*
X14500D03*
X30500D03*
X38229Y256748D03*
X34229D03*
X42309D03*
X55500Y292712D03*
X38500Y983484D03*
X34500D03*
X42500D03*
X72561Y1019484D03*
X56500D03*
X143500Y256748D03*
X127482Y256712D03*
X139500Y256748D03*
X135500D03*
X142500Y986669D03*
X126500D03*
X138500D03*
X134500D03*
X162420Y256748D03*
X158420D03*
X154000D03*
X166420D03*
X167000Y292712D03*
X161920Y986669D03*
X157920D03*
X153500D03*
X166000D03*
X169500Y1019484D03*
X183000Y292712D03*
X181500Y1019484D03*
G54D30*
X25984Y253500D03*
Y980500D03*
X40484Y664500D03*
X40547Y660519D03*
Y656519D03*
X40484Y668500D03*
Y684500D03*
Y680500D03*
Y672500D03*
Y676500D03*
G54D21*
X16142Y223012D03*
X17717D03*
X19292D03*
X20867D03*
X22442D03*
X24016D03*
X25591D03*
X27166D03*
X28741D03*
X30316D03*
Y241516D03*
X28741D03*
X27166D03*
X25591D03*
X24016D03*
X22442D03*
X20867D03*
X19292D03*
X17717D03*
X16142D03*
Y949784D03*
X17717D03*
X19292D03*
X20867D03*
X22442D03*
X24016D03*
X25591D03*
X27166D03*
X28741D03*
X30316D03*
Y968288D03*
X28741D03*
X27166D03*
X25591D03*
X24016D03*
X22442D03*
X20867D03*
X19292D03*
X17717D03*
X16142D03*
X49036Y304940D03*
X50611D03*
X52186D03*
X53761D03*
Y323444D03*
X52186D03*
X50611D03*
X49036D03*
X49536Y1031712D03*
X51111D03*
X52686D03*
X54261D03*
Y1050216D03*
X52686D03*
X51111D03*
X49536D03*
X55336Y304940D03*
X56910D03*
X58485D03*
X60060D03*
X61635D03*
X63210D03*
Y323444D03*
X61635D03*
X60060D03*
X58485D03*
X56910D03*
X55336D03*
X55836Y1031712D03*
X57410D03*
X58985D03*
X60560D03*
X62135D03*
X63710D03*
Y1050216D03*
X62135D03*
X60560D03*
X58985D03*
X57410D03*
X55836D03*
X139833Y223012D03*
X141408D03*
X142983D03*
X144558D03*
X146133D03*
Y241516D03*
X144558D03*
X142983D03*
X141408D03*
X139833D03*
Y952933D03*
X141408D03*
X142983D03*
X144558D03*
X146133D03*
Y971437D03*
X144558D03*
X142983D03*
X141408D03*
X139833D03*
X147707Y223012D03*
X149282D03*
X150857D03*
X152432D03*
X154007D03*
Y241516D03*
X152432D03*
X150857D03*
X149282D03*
X147707D03*
X158333Y304940D03*
X159908D03*
X161483D03*
X163058D03*
X164633D03*
X166207D03*
X167782D03*
X169357D03*
Y323444D03*
X167782D03*
X166207D03*
X164633D03*
X163058D03*
X161483D03*
X159908D03*
X158333D03*
X147707Y952933D03*
X149282D03*
X150857D03*
X152432D03*
X154007D03*
Y971437D03*
X152432D03*
X150857D03*
X149282D03*
X147707D03*
X158333Y1031712D03*
X159908D03*
X161483D03*
X163058D03*
X164633D03*
X166207D03*
X167782D03*
X169357D03*
Y1050216D03*
X167782D03*
X166207D03*
X164633D03*
X163058D03*
X161483D03*
X159908D03*
X158333D03*
X170932Y304940D03*
X172507D03*
Y323444D03*
X170932D03*
Y1031712D03*
X172507D03*
Y1050216D03*
X170932D03*
G54D22*
X32874Y223012D03*
Y949784D03*
X65768Y304940D03*
X66268Y1031712D03*
X156565Y223012D03*
Y952933D03*
X175065Y304940D03*
Y1031712D03*
G54D13*
X7000Y253745D03*
X6500Y980517D03*
X19000Y253781D03*
X15000D03*
X30000D03*
X18500Y980517D03*
X14500D03*
X30500D03*
X38229Y253781D03*
X34229D03*
X42309D03*
X55500Y289745D03*
X38500Y980517D03*
X34500D03*
X42500D03*
X72561Y1016517D03*
X56500D03*
X143500Y253781D03*
X127482Y253745D03*
X139500Y253781D03*
X135500D03*
X142500Y983702D03*
X126500D03*
X138500D03*
X134500D03*
X162420Y253781D03*
X158420D03*
X154000D03*
X166420D03*
X167000Y289745D03*
X161920Y983702D03*
X157920D03*
X153500D03*
X166000D03*
X169500Y1016517D03*
X183000Y289745D03*
X181500Y1016517D03*
G54D31*
X23017Y253500D03*
Y980500D03*
X37517Y664500D03*
X37580Y660519D03*
Y656519D03*
X37517Y668500D03*
Y684500D03*
Y680500D03*
Y672500D03*
Y676500D03*
G54D40*
X20000Y1307000D03*
X44000Y17500D03*
X178500D03*
G54D50*
G01X0Y1311024D02*
Y15748D01*
G01D02*
G03X15748Y0I15748J0D01*
G01Y1326772D02*
G03X0Y1311024I0J-15748D01*
G01X15748Y0D02*
X58898D01*
G01X187795Y1326772D02*
X15748D01*
G01X58898Y0D02*
X64803Y5906D01*
G01D02*
Y43307D01*
G01X74252D02*
Y7283D01*
G01D02*
X80157Y1378D01*
G01X64803Y43307D02*
G02X74252I4724J0D01*
G01X80157Y1378D02*
X99488D01*
G01D02*
X105394Y7283D01*
G01D02*
Y43307D01*
G01X108150D02*
Y7283D01*
G01D02*
X114055Y1378D01*
G01D02*
X123386D01*
G01D02*
X129291Y7283D01*
G01X105394Y43307D02*
G02X108150I1378J0D01*
G01X138740Y5906D02*
X144646Y0D01*
G01D02*
X187795D01*
G01X129291Y7283D02*
Y43307D01*
G01X138740D02*
Y5906D01*
G01X129291Y43307D02*
G02X138740I4724J0D01*
G01X187795Y0D02*
G03X203543Y15748I0J15748D01*
G01Y1311024D02*
G03X187795Y1326772I-15748J0D01*
G01X203543Y15748D02*
Y1311024D01*
G54D41*
X40667Y241228D03*
Y234228D03*
X38685Y305228D03*
Y312228D03*
X40867Y962300D03*
Y969300D03*
X39055Y1030668D03*
Y1037668D03*
X147982Y305228D03*
Y312228D03*
Y1032000D03*
Y1039000D03*
X164358Y241228D03*
Y234228D03*
X166258Y965649D03*
Y972649D03*
G54D23*
X32874Y241516D03*
Y968288D03*
X65768Y323444D03*
X66268Y1050216D03*
X156565Y241516D03*
Y971437D03*
X175065Y323444D03*
Y1050216D03*
G54D32*
X11000Y253780D03*
X10500Y980516D03*
X41123Y289708D03*
X45123D03*
X49000Y289716D03*
X37061Y289708D03*
X42123Y1016480D03*
X46123D03*
X50000Y1016516D03*
X38061Y1016480D03*
X59500Y289744D03*
X63500D03*
X68061D03*
X60500Y1016516D03*
X76561D03*
X64500D03*
X68561D03*
X131500Y253780D03*
X147500D03*
X130500Y983701D03*
X146500D03*
X147500Y1016516D03*
X171000Y289744D03*
X152420Y289708D03*
X156420D03*
X160500Y289744D03*
X148500Y289708D03*
X165500Y1016516D03*
X151420Y1016480D03*
X155420D03*
X159500Y1016516D03*
X187000Y289744D03*
X175000D03*
X179000D03*
X185500Y1016516D03*
X173500D03*
X177500D03*
G54D14*
X30315Y41378D03*
Y404764D03*
Y768150D03*
Y1131536D03*
X173228Y111456D03*
Y474842D03*
Y838228D03*
Y1201614D03*
G54D51*
G01X-320500Y-470483D02*
Y2626000D01*
X2967000D01*
Y-470483D01*
X-320500D01*
G01X329322Y-314459D02*
Y-319459D01*
G01X327865Y-314459D02*
X330779D01*
G01X335689Y-319459D02*
X333155D01*
Y-314459D01*
X335689D01*
G01X334675Y-316876D02*
X333155D01*
G01X338255Y-314459D02*
Y-319459D01*
X340789D01*
G01X344622Y-319626D02*
X344495Y-319542D01*
Y-319376D01*
X344622Y-319292D01*
X344749Y-319376D01*
Y-319542D01*
X344622Y-319626D01*
G01Y-317376D02*
X344495Y-317292D01*
Y-317126D01*
X344622Y-317042D01*
X344749Y-317126D01*
Y-317292D01*
X344622Y-317376D01*
G01X349405Y-321126D02*
X348772Y-320292D01*
X348455Y-319459D01*
Y-316126D01*
X348772Y-315292D01*
X349405Y-314459D01*
G01X354822D02*
X354315Y-314626D01*
X353935Y-315042D01*
X353682Y-315542D01*
X353492Y-316209D01*
X353429Y-316959D01*
X353492Y-317709D01*
X353682Y-318376D01*
X353935Y-318876D01*
X354315Y-319292D01*
X354822Y-319459D01*
X355329Y-319292D01*
X355709Y-318876D01*
X355962Y-318376D01*
X356152Y-317709D01*
X356215Y-316959D01*
X356152Y-316209D01*
X355962Y-315542D01*
X355709Y-315042D01*
X355329Y-314626D01*
X354822Y-314459D01*
G01X358529Y-318459D02*
X358909Y-319042D01*
X359415Y-319376D01*
X359985Y-319459D01*
X360492Y-319376D01*
X360999Y-318959D01*
X361315Y-318459D01*
X361379Y-317959D01*
X361252Y-317376D01*
X360809Y-316959D01*
X360365Y-316792D01*
X359795D01*
G01X360365D02*
X360745Y-316542D01*
X361062Y-316126D01*
X361189Y-315626D01*
X361062Y-315126D01*
X360745Y-314709D01*
X360175Y-314459D01*
X359605Y-314542D01*
X359035Y-314876D01*
G01X365339Y-321126D02*
X365972Y-320292D01*
X366289Y-319459D01*
Y-316126D01*
X365972Y-315292D01*
X365339Y-314459D01*
G01X368729Y-318459D02*
X369109Y-319042D01*
X369615Y-319376D01*
X370185Y-319459D01*
X370692Y-319376D01*
X371199Y-318959D01*
X371515Y-318459D01*
X371579Y-317959D01*
X371452Y-317376D01*
X371009Y-316959D01*
X370565Y-316792D01*
X369995D01*
G01X370565D02*
X370945Y-316542D01*
X371262Y-316126D01*
X371389Y-315626D01*
X371262Y-315126D01*
X370945Y-314709D01*
X370375Y-314459D01*
X369805Y-314542D01*
X369235Y-314876D01*
G01X374019Y-315292D02*
X374399Y-314792D01*
X374842Y-314542D01*
X375349Y-314459D01*
X375982Y-314626D01*
X376425Y-315042D01*
X376552Y-315542D01*
X376489Y-316042D01*
X376235Y-316459D01*
X374969Y-317292D01*
X374399Y-317876D01*
X374019Y-318709D01*
X373892Y-319459D01*
X376552D01*
G01X380195D02*
X380322Y-318376D01*
X380512Y-317459D01*
X380765Y-316626D01*
X381082Y-315709D01*
X381589Y-314459D01*
X379055D01*
G01X384599Y-317792D02*
X386245D01*
G01X389319Y-315292D02*
X389699Y-314792D01*
X390142Y-314542D01*
X390649Y-314459D01*
X391282Y-314626D01*
X391725Y-315042D01*
X391852Y-315542D01*
X391789Y-316042D01*
X391535Y-316459D01*
X390269Y-317292D01*
X389699Y-317876D01*
X389319Y-318709D01*
X389192Y-319459D01*
X391852D01*
G01X394229Y-318459D02*
X394609Y-319042D01*
X395115Y-319376D01*
X395685Y-319459D01*
X396192Y-319376D01*
X396699Y-318959D01*
X397015Y-318459D01*
X397079Y-317959D01*
X396952Y-317376D01*
X396509Y-316959D01*
X396065Y-316792D01*
X395495D01*
G01X396065D02*
X396445Y-316542D01*
X396762Y-316126D01*
X396889Y-315626D01*
X396762Y-315126D01*
X396445Y-314709D01*
X395875Y-314459D01*
X395305Y-314542D01*
X394735Y-314876D01*
G01X401482Y-319459D02*
Y-314459D01*
X399139Y-318042D01*
X402305D01*
G01X404429Y-318709D02*
X404809Y-319126D01*
X405252Y-319376D01*
X405822Y-319459D01*
X406392Y-319292D01*
X406835Y-318959D01*
X407152Y-318376D01*
X407215Y-317709D01*
X407089Y-317042D01*
X406772Y-316626D01*
X406329Y-316292D01*
X405885Y-316209D01*
X405442Y-316292D01*
X404872Y-316626D01*
X405062Y-314459D01*
X406772D01*
G01X414819Y-319459D02*
Y-314459D01*
X417225D01*
G01X416339Y-316876D02*
X414819D01*
G01X419539Y-319459D02*
X421122Y-314459D01*
X422705Y-319459D01*
G01X422135Y-317709D02*
X420109D01*
G01X424892Y-319459D02*
X427552Y-314459D01*
G01X424892D02*
X427552Y-319459D01*
G01X431322Y-319626D02*
X431195Y-319542D01*
Y-319376D01*
X431322Y-319292D01*
X431449Y-319376D01*
Y-319542D01*
X431322Y-319626D01*
G01Y-317376D02*
X431195Y-317292D01*
Y-317126D01*
X431322Y-317042D01*
X431449Y-317126D01*
Y-317292D01*
X431322Y-317376D01*
G01X436105Y-321126D02*
X435472Y-320292D01*
X435155Y-319459D01*
Y-316126D01*
X435472Y-315292D01*
X436105Y-314459D01*
G01X441522D02*
X441015Y-314626D01*
X440635Y-315042D01*
X440382Y-315542D01*
X440192Y-316209D01*
X440129Y-316959D01*
X440192Y-317709D01*
X440382Y-318376D01*
X440635Y-318876D01*
X441015Y-319292D01*
X441522Y-319459D01*
X442029Y-319292D01*
X442409Y-318876D01*
X442662Y-318376D01*
X442852Y-317709D01*
X442915Y-316959D01*
X442852Y-316209D01*
X442662Y-315542D01*
X442409Y-315042D01*
X442029Y-314626D01*
X441522Y-314459D01*
G01X445229Y-318459D02*
X445609Y-319042D01*
X446115Y-319376D01*
X446685Y-319459D01*
X447192Y-319376D01*
X447699Y-318959D01*
X448015Y-318459D01*
X448079Y-317959D01*
X447952Y-317376D01*
X447509Y-316959D01*
X447065Y-316792D01*
X446495D01*
G01X447065D02*
X447445Y-316542D01*
X447762Y-316126D01*
X447889Y-315626D01*
X447762Y-315126D01*
X447445Y-314709D01*
X446875Y-314459D01*
X446305Y-314542D01*
X445735Y-314876D01*
G01X452039Y-321126D02*
X452672Y-320292D01*
X452989Y-319459D01*
Y-316126D01*
X452672Y-315292D01*
X452039Y-314459D01*
G01X455429Y-318459D02*
X455809Y-319042D01*
X456315Y-319376D01*
X456885Y-319459D01*
X457392Y-319376D01*
X457899Y-318959D01*
X458215Y-318459D01*
X458279Y-317959D01*
X458152Y-317376D01*
X457709Y-316959D01*
X457265Y-316792D01*
X456695D01*
G01X457265D02*
X457645Y-316542D01*
X457962Y-316126D01*
X458089Y-315626D01*
X457962Y-315126D01*
X457645Y-314709D01*
X457075Y-314459D01*
X456505Y-314542D01*
X455935Y-314876D01*
G01X460845Y-318876D02*
X461289Y-319292D01*
X461795Y-319459D01*
X462302Y-319292D01*
X462745Y-318792D01*
X463062Y-318042D01*
X463189Y-317292D01*
Y-316376D01*
X463062Y-315626D01*
X462745Y-314959D01*
X462365Y-314626D01*
X461922Y-314459D01*
X461415Y-314626D01*
X461035Y-314959D01*
X460782Y-315459D01*
X460655Y-316126D01*
X460782Y-316709D01*
X461099Y-317292D01*
X461479Y-317626D01*
X461922Y-317709D01*
X462429Y-317542D01*
X462809Y-317126D01*
X463189Y-316376D01*
G01X466895Y-319459D02*
X467022Y-318376D01*
X467212Y-317459D01*
X467465Y-316626D01*
X467782Y-315709D01*
X468289Y-314459D01*
X465755D01*
G01X471299Y-317792D02*
X472945D01*
G01X475829Y-318459D02*
X476209Y-319042D01*
X476715Y-319376D01*
X477285Y-319459D01*
X477792Y-319376D01*
X478299Y-318959D01*
X478615Y-318459D01*
X478679Y-317959D01*
X478552Y-317376D01*
X478109Y-316959D01*
X477665Y-316792D01*
X477095D01*
G01X477665D02*
X478045Y-316542D01*
X478362Y-316126D01*
X478489Y-315626D01*
X478362Y-315126D01*
X478045Y-314709D01*
X477475Y-314459D01*
X476905Y-314542D01*
X476335Y-314876D01*
G01X481119Y-317376D02*
X481562Y-316792D01*
X481942Y-316459D01*
X482449Y-316292D01*
X482892Y-316459D01*
X483209Y-316792D01*
X483462Y-317292D01*
X483525Y-317876D01*
X483462Y-318376D01*
X483209Y-318876D01*
X482829Y-319292D01*
X482385Y-319459D01*
X481879Y-319292D01*
X481435Y-318792D01*
X481182Y-318042D01*
X481119Y-317209D01*
X481245Y-316126D01*
X481435Y-315542D01*
X481752Y-314959D01*
X482195Y-314542D01*
X482639Y-314459D01*
X483082Y-314626D01*
X483399Y-315042D01*
G01X487422Y-319459D02*
Y-314459D01*
X486662Y-315459D01*
G01Y-319459D02*
X488182D01*
G01X493282D02*
Y-314459D01*
X490939Y-318042D01*
X494105D01*
G01X317322Y-249459D02*
Y-324459D01*
X817322D01*
Y-249459D01*
X317322D01*
G01X512322D02*
Y-324459D01*
G01Y-299459D02*
X615322D01*
Y-274459D01*
G01X512322D02*
X615322D01*
G01X622829Y-309459D02*
Y-304459D01*
X624095D01*
X624602Y-304709D01*
X624982Y-305042D01*
X625299Y-305542D01*
X625552Y-306126D01*
X625615Y-306959D01*
X625552Y-307792D01*
X625299Y-308376D01*
X624982Y-308876D01*
X624602Y-309209D01*
X624095Y-309459D01*
X622829D01*
G01X627739D02*
X629322Y-304459D01*
X630905Y-309459D01*
G01X630335Y-307709D02*
X628309D01*
G01X634422Y-304459D02*
Y-309459D01*
G01X632965Y-304459D02*
X635879D01*
G01X640789Y-309459D02*
X638255D01*
Y-304459D01*
X640789D01*
G01X639775Y-306876D02*
X638255D01*
G01X644622Y-309626D02*
X644495Y-309542D01*
Y-309376D01*
X644622Y-309292D01*
X644749Y-309376D01*
Y-309542D01*
X644622Y-309626D01*
G01Y-307376D02*
X644495Y-307292D01*
Y-307126D01*
X644622Y-307042D01*
X644749Y-307126D01*
Y-307292D01*
X644622Y-307376D01*
G01X617322Y-249459D02*
Y-324459D01*
G01X615322Y-249459D02*
Y-324459D01*
G01X622955Y-284459D02*
Y-279459D01*
X624475D01*
X624982Y-279709D01*
X625362Y-280292D01*
X625489Y-280959D01*
X625362Y-281626D01*
X625045Y-282126D01*
X624475Y-282376D01*
X622955D01*
G01X628182Y-284626D02*
X630462Y-279459D01*
G01X632965Y-284459D02*
Y-279459D01*
X635879Y-284459D01*
Y-279459D01*
G01X639522Y-284626D02*
X639395Y-284542D01*
Y-284376D01*
X639522Y-284292D01*
X639649Y-284376D01*
Y-284542D01*
X639522Y-284626D01*
G01Y-282376D02*
X639395Y-282292D01*
Y-282126D01*
X639522Y-282042D01*
X639649Y-282126D01*
Y-282292D01*
X639522Y-282376D01*
G01X617322Y-299459D02*
X817322D01*
G01X622955Y-259459D02*
Y-254459D01*
X624475D01*
X624982Y-254709D01*
X625362Y-255292D01*
X625489Y-255959D01*
X625362Y-256626D01*
X625045Y-257126D01*
X624475Y-257376D01*
X622955D01*
G01X628055Y-259459D02*
Y-254459D01*
X629639D01*
X630145Y-254709D01*
X630462Y-255042D01*
X630589Y-255709D01*
X630462Y-256376D01*
X630082Y-256792D01*
X629639Y-257042D01*
X628055D01*
G01X629639D02*
X630589Y-259459D01*
G01X634422D02*
X633915Y-259376D01*
X633472Y-259042D01*
X633092Y-258542D01*
X632839Y-257959D01*
X632712Y-257292D01*
Y-256626D01*
X632839Y-255959D01*
X633092Y-255376D01*
X633472Y-254876D01*
X633915Y-254542D01*
X634422Y-254459D01*
X634929Y-254542D01*
X635372Y-254876D01*
X635752Y-255376D01*
X636005Y-255959D01*
X636132Y-256626D01*
Y-257292D01*
X636005Y-257959D01*
X635752Y-258542D01*
X635372Y-259042D01*
X634929Y-259376D01*
X634422Y-259459D01*
G01X638255Y-258459D02*
X638572Y-258959D01*
X638952Y-259292D01*
X639395Y-259459D01*
X639902Y-259292D01*
X640282Y-258959D01*
X640662Y-258459D01*
X640789Y-257792D01*
Y-254459D01*
G01X645889Y-259459D02*
X643355D01*
Y-254459D01*
X645889D01*
G01X644875Y-256876D02*
X643355D01*
G01X651115Y-254876D02*
X650735Y-254626D01*
X650292Y-254459D01*
X649785D01*
X649215Y-254709D01*
X648772Y-255126D01*
X648455Y-255626D01*
X648202Y-256459D01*
X648139Y-257209D01*
X648265Y-257959D01*
X648455Y-258459D01*
X648835Y-258959D01*
X649279Y-259292D01*
X649722Y-259459D01*
X650165D01*
X650609Y-259292D01*
X650989Y-259042D01*
X651305Y-258709D01*
G01X654822Y-254459D02*
Y-259459D01*
G01X653365Y-254459D02*
X656279D01*
G01X659922Y-259626D02*
X659795Y-259542D01*
Y-259376D01*
X659922Y-259292D01*
X660049Y-259376D01*
Y-259542D01*
X659922Y-259626D01*
G01Y-257376D02*
X659795Y-257292D01*
Y-257126D01*
X659922Y-257042D01*
X660049Y-257126D01*
Y-257292D01*
X659922Y-257376D01*
G01X617322Y-274459D02*
X817322D01*
G01X734955Y-301959D02*
Y-306959D01*
X737489D01*
G01X740562Y-301959D02*
X742082D01*
G01X741322D02*
Y-306959D01*
G01X740562D02*
X742082D01*
G01X746929Y-304292D02*
X747182Y-304042D01*
X747372Y-303626D01*
X747499Y-303042D01*
X747372Y-302542D01*
X747119Y-302209D01*
X746675Y-301959D01*
X744965D01*
Y-306959D01*
X747055D01*
X747499Y-306626D01*
X747752Y-306126D01*
X747879Y-305542D01*
X747752Y-304959D01*
X747372Y-304459D01*
X746929Y-304292D01*
X744965D01*
G01X751522Y-307126D02*
X751395Y-307042D01*
Y-306876D01*
X751522Y-306792D01*
X751649Y-306876D01*
Y-307042D01*
X751522Y-307126D01*
G01Y-304876D02*
X751395Y-304792D01*
Y-304626D01*
X751522Y-304542D01*
X751649Y-304626D01*
Y-304792D01*
X751522Y-304876D01*
G01X732322Y-299459D02*
Y-324459D01*
G01X779222Y-301959D02*
Y-306959D01*
G01X777765Y-301959D02*
X780679D01*
G01X784322Y-306959D02*
X783942Y-306876D01*
X783562Y-306542D01*
X783309Y-305959D01*
X783182Y-305292D01*
X783309Y-304626D01*
X783562Y-304042D01*
X783942Y-303709D01*
X784322Y-303626D01*
X784702Y-303709D01*
X785082Y-304042D01*
X785335Y-304626D01*
X785399Y-305292D01*
X785335Y-305959D01*
X785082Y-306542D01*
X784702Y-306876D01*
X784322Y-306959D01*
G01X789422D02*
X789042Y-306876D01*
X788662Y-306542D01*
X788409Y-305959D01*
X788282Y-305292D01*
X788409Y-304626D01*
X788662Y-304042D01*
X789042Y-303709D01*
X789422Y-303626D01*
X789802Y-303709D01*
X790182Y-304042D01*
X790435Y-304626D01*
X790499Y-305292D01*
X790435Y-305959D01*
X790182Y-306542D01*
X789802Y-306876D01*
X789422Y-306959D01*
G01X794522D02*
Y-301959D01*
G01X799622Y-307126D02*
X799495Y-307042D01*
Y-306876D01*
X799622Y-306792D01*
X799749Y-306876D01*
Y-307042D01*
X799622Y-307126D01*
G01Y-304876D02*
X799495Y-304792D01*
Y-304626D01*
X799622Y-304542D01*
X799749Y-304626D01*
Y-304792D01*
X799622Y-304876D01*
G01X775322Y-299459D02*
Y-324459D01*
G01Y-274459D02*
Y-299459D01*
G01X777955Y-281959D02*
Y-276959D01*
X779539D01*
X780045Y-277209D01*
X780362Y-277542D01*
X780489Y-278209D01*
X780362Y-278876D01*
X779982Y-279292D01*
X779539Y-279542D01*
X777955D01*
G01X779539D02*
X780489Y-281959D01*
G01X785589D02*
X783055D01*
Y-276959D01*
X785589D01*
G01X784575Y-279376D02*
X783055D01*
G01X787839Y-276959D02*
X789422Y-281959D01*
X791005Y-276959D01*
G01X794522Y-282126D02*
X794395Y-282042D01*
Y-281876D01*
X794522Y-281792D01*
X794649Y-281876D01*
Y-282042D01*
X794522Y-282126D01*
G01Y-279876D02*
X794395Y-279792D01*
Y-279626D01*
X794522Y-279542D01*
X794649Y-279626D01*
Y-279792D01*
X794522Y-279876D01*
G01X798082Y-326159D02*
X798162Y-326084D01*
X798222Y-325959D01*
X798262Y-325784D01*
X798222Y-325634D01*
X798142Y-325534D01*
X798002Y-325459D01*
X797462D01*
Y-326959D01*
X798122D01*
X798262Y-326859D01*
X798342Y-326709D01*
X798382Y-326534D01*
X798342Y-326359D01*
X798222Y-326209D01*
X798082Y-326159D01*
X797462D01*
G01X799482Y-326959D02*
Y-325959D01*
G01Y-326134D02*
X799402Y-326034D01*
X799282Y-325984D01*
X799142Y-325959D01*
X799002Y-326009D01*
X798882Y-326109D01*
X798802Y-326259D01*
X798762Y-326459D01*
X798802Y-326659D01*
X798882Y-326809D01*
X799002Y-326909D01*
X799142Y-326959D01*
X799282Y-326934D01*
X799402Y-326859D01*
X799482Y-326759D01*
G01X800022Y-326784D02*
X800122Y-326884D01*
X800262Y-326959D01*
X800382D01*
X800502Y-326909D01*
X800582Y-326834D01*
X800622Y-326734D01*
X800602Y-326584D01*
X800522Y-326509D01*
X800162Y-326359D01*
X800082Y-326184D01*
X800122Y-326059D01*
X800202Y-325984D01*
X800322Y-325959D01*
X800442Y-325984D01*
X800562Y-326059D01*
G01X801222Y-326284D02*
X801862D01*
X801802Y-326109D01*
X801702Y-326009D01*
X801562Y-325959D01*
X801422Y-325984D01*
X801302Y-326059D01*
X801222Y-326234D01*
X801182Y-326384D01*
Y-326534D01*
X801222Y-326684D01*
X801322Y-326834D01*
X801442Y-326934D01*
X801582Y-326959D01*
X801722Y-326909D01*
X801862Y-326759D01*
G01X802362Y-326959D02*
Y-325459D01*
G01Y-326209D02*
X802462Y-326059D01*
X802582Y-325984D01*
X802702Y-325959D01*
X802882Y-326009D01*
X803002Y-326109D01*
X803082Y-326284D01*
Y-326484D01*
X803042Y-326684D01*
X802962Y-326834D01*
X802822Y-326934D01*
X802702Y-326959D01*
X802582Y-326934D01*
X802462Y-326859D01*
X802362Y-326734D01*
G01X803922Y-326959D02*
X803802Y-326934D01*
X803682Y-326834D01*
X803602Y-326659D01*
X803562Y-326459D01*
X803602Y-326259D01*
X803682Y-326084D01*
X803802Y-325984D01*
X803922Y-325959D01*
X804042Y-325984D01*
X804162Y-326084D01*
X804242Y-326259D01*
X804262Y-326459D01*
X804242Y-326659D01*
X804162Y-326834D01*
X804042Y-326934D01*
X803922Y-326959D01*
G01X805482D02*
Y-325959D01*
G01Y-326134D02*
X805402Y-326034D01*
X805282Y-325984D01*
X805142Y-325959D01*
X805002Y-326009D01*
X804882Y-326109D01*
X804802Y-326259D01*
X804762Y-326459D01*
X804802Y-326659D01*
X804882Y-326809D01*
X805002Y-326909D01*
X805142Y-326959D01*
X805282Y-326934D01*
X805402Y-326859D01*
X805482Y-326759D01*
G01X806042Y-326959D02*
Y-325959D01*
G01Y-326159D02*
X806142Y-326059D01*
X806242Y-325984D01*
X806382Y-325959D01*
X806482Y-325984D01*
X806602Y-326059D01*
G01X807882Y-325459D02*
Y-326959D01*
G01Y-326734D02*
X807802Y-326859D01*
X807682Y-326934D01*
X807542Y-326959D01*
X807382Y-326909D01*
X807262Y-326784D01*
X807182Y-326634D01*
X807162Y-326459D01*
X807182Y-326284D01*
X807262Y-326134D01*
X807382Y-326009D01*
X807542Y-325959D01*
X807682Y-325984D01*
X807782Y-326034D01*
X807882Y-326134D01*
G01X809522Y-326959D02*
Y-325459D01*
X810022D01*
X810182Y-325534D01*
X810282Y-325634D01*
X810322Y-325834D01*
X810282Y-326034D01*
X810162Y-326159D01*
X810022Y-326234D01*
X809522D01*
G01X810022D02*
X810322Y-326959D01*
G01X810822Y-326284D02*
X811462D01*
X811402Y-326109D01*
X811302Y-326009D01*
X811162Y-325959D01*
X811022Y-325984D01*
X810902Y-326059D01*
X810822Y-326234D01*
X810782Y-326384D01*
Y-326534D01*
X810822Y-326684D01*
X810922Y-326834D01*
X811042Y-326934D01*
X811182Y-326959D01*
X811322Y-326909D01*
X811462Y-326759D01*
G01X811962Y-325959D02*
X812322Y-326959D01*
X812682Y-325959D01*
G01X813522Y-327009D02*
X813482Y-326984D01*
Y-326934D01*
X813522Y-326909D01*
X813562Y-326934D01*
Y-326984D01*
X813522Y-327009D01*
G01X814682Y-326959D02*
X814722Y-326634D01*
X814782Y-326359D01*
X814862Y-326109D01*
X814962Y-325834D01*
X815122Y-325459D01*
X814322D01*
G01X816082Y-326159D02*
X816162Y-326084D01*
X816222Y-325959D01*
X816262Y-325784D01*
X816222Y-325634D01*
X816142Y-325534D01*
X816002Y-325459D01*
X815462D01*
Y-326959D01*
X816122D01*
X816262Y-326859D01*
X816342Y-326709D01*
X816382Y-326534D01*
X816342Y-326359D01*
X816222Y-326209D01*
X816082Y-326159D01*
X815462D01*
G01X-320500Y-470483D02*
Y2626000D01*
X2967000D01*
Y-470483D01*
X-320500D01*
G01X331395Y-304184D02*
X330925Y-303869D01*
X330377Y-303659D01*
X329750D01*
X329045Y-303974D01*
X328497Y-304499D01*
X328105Y-305129D01*
X327792Y-306179D01*
X327714Y-307124D01*
X327870Y-308069D01*
X328105Y-308699D01*
X328575Y-309329D01*
X329124Y-309749D01*
X329672Y-309959D01*
X330220D01*
X330769Y-309749D01*
X331239Y-309434D01*
X331630Y-309014D01*
G01X335032Y-303659D02*
X336912D01*
G01X335972D02*
Y-309959D01*
G01X335032D02*
X336912D01*
G01X342272Y-303659D02*
Y-309959D01*
G01X340470Y-303659D02*
X344074D01*
G01X348572Y-309959D02*
Y-307124D01*
X347005Y-303659D01*
G01X350139D02*
X348572Y-307124D01*
G01X359449Y-308699D02*
X359919Y-309434D01*
X360545Y-309854D01*
X361250Y-309959D01*
X361877Y-309854D01*
X362504Y-309329D01*
X362895Y-308699D01*
X362974Y-308069D01*
X362817Y-307334D01*
X362269Y-306809D01*
X361720Y-306599D01*
X361015D01*
G01X361720D02*
X362190Y-306284D01*
X362582Y-305759D01*
X362739Y-305129D01*
X362582Y-304499D01*
X362190Y-303974D01*
X361485Y-303659D01*
X360780Y-303764D01*
X360075Y-304184D01*
G01X365749Y-308699D02*
X366219Y-309434D01*
X366845Y-309854D01*
X367550Y-309959D01*
X368177Y-309854D01*
X368804Y-309329D01*
X369195Y-308699D01*
X369274Y-308069D01*
X369117Y-307334D01*
X368569Y-306809D01*
X368020Y-306599D01*
X367315D01*
G01X368020D02*
X368490Y-306284D01*
X368882Y-305759D01*
X369039Y-305129D01*
X368882Y-304499D01*
X368490Y-303974D01*
X367785Y-303659D01*
X367080Y-303764D01*
X366375Y-304184D01*
G01X372049Y-308699D02*
X372519Y-309434D01*
X373145Y-309854D01*
X373850Y-309959D01*
X374477Y-309854D01*
X375104Y-309329D01*
X375495Y-308699D01*
X375574Y-308069D01*
X375417Y-307334D01*
X374869Y-306809D01*
X374320Y-306599D01*
X373615D01*
G01X374320D02*
X374790Y-306284D01*
X375182Y-305759D01*
X375339Y-305129D01*
X375182Y-304499D01*
X374790Y-303974D01*
X374085Y-303659D01*
X373380Y-303764D01*
X372675Y-304184D01*
G01X379915Y-309959D02*
X380072Y-308594D01*
X380307Y-307439D01*
X380620Y-306389D01*
X381012Y-305234D01*
X381639Y-303659D01*
X378505D01*
G01X386215Y-309959D02*
X386372Y-308594D01*
X386607Y-307439D01*
X386920Y-306389D01*
X387312Y-305234D01*
X387939Y-303659D01*
X384805D01*
G01X392515Y-311114D02*
X392829Y-309749D01*
G01X398972Y-303659D02*
Y-309959D01*
G01X397170Y-303659D02*
X400774D01*
G01X403314Y-309959D02*
X405272Y-303659D01*
X407230Y-309959D01*
G01X406525Y-307754D02*
X404019D01*
G01X410632Y-303659D02*
X412512D01*
G01X411572D02*
Y-309959D01*
G01X410632D02*
X412512D01*
G01X415522Y-303659D02*
X416619Y-309959D01*
X417872Y-303659D01*
X419125Y-309959D01*
X420222Y-303659D01*
G01X422214Y-309959D02*
X424172Y-303659D01*
X426130Y-309959D01*
G01X425425Y-307754D02*
X422919D01*
G01X428670Y-309959D02*
Y-303659D01*
X432274Y-309959D01*
Y-303659D01*
G01X442680Y-312059D02*
X441897Y-311009D01*
X441505Y-309959D01*
Y-305759D01*
X441897Y-304709D01*
X442680Y-303659D01*
G01X454105Y-309959D02*
Y-303659D01*
X456064D01*
X456690Y-303974D01*
X457082Y-304394D01*
X457239Y-305234D01*
X457082Y-306074D01*
X456612Y-306599D01*
X456064Y-306914D01*
X454105D01*
G01X456064D02*
X457239Y-309959D01*
G01X461972Y-310169D02*
X461815Y-310064D01*
Y-309854D01*
X461972Y-309749D01*
X462129Y-309854D01*
Y-310064D01*
X461972Y-310169D01*
G01X468272Y-309959D02*
X467645Y-309854D01*
X467097Y-309434D01*
X466627Y-308804D01*
X466314Y-308069D01*
X466157Y-307229D01*
Y-306389D01*
X466314Y-305549D01*
X466627Y-304814D01*
X467097Y-304184D01*
X467645Y-303764D01*
X468272Y-303659D01*
X468899Y-303764D01*
X469447Y-304184D01*
X469917Y-304814D01*
X470230Y-305549D01*
X470387Y-306389D01*
Y-307229D01*
X470230Y-308069D01*
X469917Y-308804D01*
X469447Y-309434D01*
X468899Y-309854D01*
X468272Y-309959D01*
G01X474572Y-310169D02*
X474415Y-310064D01*
Y-309854D01*
X474572Y-309749D01*
X474729Y-309854D01*
Y-310064D01*
X474572Y-310169D01*
G01X482595Y-304184D02*
X482125Y-303869D01*
X481577Y-303659D01*
X480950D01*
X480245Y-303974D01*
X479697Y-304499D01*
X479305Y-305129D01*
X478992Y-306179D01*
X478914Y-307124D01*
X479070Y-308069D01*
X479305Y-308699D01*
X479775Y-309329D01*
X480324Y-309749D01*
X480872Y-309959D01*
X481420D01*
X481969Y-309749D01*
X482439Y-309434D01*
X482830Y-309014D01*
G01X487172Y-310169D02*
X487015Y-310064D01*
Y-309854D01*
X487172Y-309749D01*
X487329Y-309854D01*
Y-310064D01*
X487172Y-310169D01*
G01X493864Y-312059D02*
X494647Y-311009D01*
X495039Y-309959D01*
Y-305759D01*
X494647Y-304709D01*
X493864Y-303659D01*
G01X330142Y-296809D02*
X331709D01*
Y-298699D01*
X331239Y-299329D01*
X330690Y-299749D01*
X329907Y-299959D01*
X329124Y-299749D01*
X328575Y-299329D01*
X328105Y-298699D01*
X327792Y-297964D01*
X327635Y-297124D01*
Y-296389D01*
X327792Y-295759D01*
X328105Y-295024D01*
X328575Y-294394D01*
X329045Y-293974D01*
X329672Y-293659D01*
X330220D01*
X330847Y-293869D01*
X331317Y-294289D01*
G01X334249Y-293659D02*
Y-298174D01*
X334562Y-299119D01*
X335189Y-299749D01*
X335972Y-299959D01*
X336755Y-299749D01*
X337382Y-299119D01*
X337695Y-298174D01*
Y-293659D01*
G01X341332D02*
X343212D01*
G01X342272D02*
Y-299959D01*
G01X341332D02*
X343212D01*
G01X346927Y-299119D02*
X347554Y-299644D01*
X348259Y-299959D01*
X348885D01*
X349512Y-299644D01*
X349982Y-299119D01*
X350217Y-298384D01*
X350060Y-297649D01*
X349669Y-297019D01*
X348964Y-296599D01*
X348024Y-296389D01*
X347475Y-295969D01*
X347240Y-295234D01*
X347397Y-294499D01*
X347789Y-293974D01*
X348337Y-293659D01*
X348885D01*
X349434Y-293869D01*
X349904Y-294394D01*
G01X353227Y-299959D02*
Y-293659D01*
G01X356517D02*
Y-299959D01*
G01Y-296809D02*
X353227D01*
G01X359214Y-299959D02*
X361172Y-293659D01*
X363130Y-299959D01*
G01X362425Y-297754D02*
X359919D01*
G01X365670Y-299959D02*
Y-293659D01*
X369274Y-299959D01*
Y-293659D01*
G01X378349Y-299959D02*
Y-293659D01*
X379915D01*
X380542Y-293974D01*
X381012Y-294394D01*
X381404Y-295024D01*
X381717Y-295759D01*
X381795Y-296809D01*
X381717Y-297859D01*
X381404Y-298594D01*
X381012Y-299224D01*
X380542Y-299644D01*
X379915Y-299959D01*
X378349D01*
G01X385432Y-293659D02*
X387312D01*
G01X386372D02*
Y-299959D01*
G01X385432D02*
X387312D01*
G01X391027Y-299119D02*
X391654Y-299644D01*
X392359Y-299959D01*
X392985D01*
X393612Y-299644D01*
X394082Y-299119D01*
X394317Y-298384D01*
X394160Y-297649D01*
X393769Y-297019D01*
X393064Y-296599D01*
X392124Y-296389D01*
X391575Y-295969D01*
X391340Y-295234D01*
X391497Y-294499D01*
X391889Y-293974D01*
X392437Y-293659D01*
X392985D01*
X393534Y-293869D01*
X394004Y-294394D01*
G01X398972Y-293659D02*
Y-299959D01*
G01X397170Y-293659D02*
X400774D01*
G01X405272Y-300169D02*
X405115Y-300064D01*
Y-299854D01*
X405272Y-299749D01*
X405429Y-299854D01*
Y-300064D01*
X405272Y-300169D01*
G01X411415Y-301114D02*
X411729Y-299749D01*
G01X417872Y-293659D02*
Y-299959D01*
G01X416070Y-293659D02*
X419674D01*
G01X422214Y-299959D02*
X424172Y-293659D01*
X426130Y-299959D01*
G01X425425Y-297754D02*
X422919D01*
G01X430472Y-299959D02*
X429845Y-299854D01*
X429297Y-299434D01*
X428827Y-298804D01*
X428514Y-298069D01*
X428357Y-297229D01*
Y-296389D01*
X428514Y-295549D01*
X428827Y-294814D01*
X429297Y-294184D01*
X429845Y-293764D01*
X430472Y-293659D01*
X431099Y-293764D01*
X431647Y-294184D01*
X432117Y-294814D01*
X432430Y-295549D01*
X432587Y-296389D01*
Y-297229D01*
X432430Y-298069D01*
X432117Y-298804D01*
X431647Y-299434D01*
X431099Y-299854D01*
X430472Y-299959D01*
G01X436772D02*
Y-297124D01*
X435205Y-293659D01*
G01X438339D02*
X436772Y-297124D01*
G01X441349Y-293659D02*
Y-298174D01*
X441662Y-299119D01*
X442289Y-299749D01*
X443072Y-299959D01*
X443855Y-299749D01*
X444482Y-299119D01*
X444795Y-298174D01*
Y-293659D01*
G01X447414Y-299959D02*
X449372Y-293659D01*
X451330Y-299959D01*
G01X450625Y-297754D02*
X448119D01*
G01X453870Y-299959D02*
Y-293659D01*
X457474Y-299959D01*
Y-293659D01*
G01X327870Y-289959D02*
Y-283659D01*
X331474Y-289959D01*
Y-283659D01*
G01X335972Y-289959D02*
X335345Y-289854D01*
X334797Y-289434D01*
X334327Y-288804D01*
X334014Y-288069D01*
X333857Y-287229D01*
Y-286389D01*
X334014Y-285549D01*
X334327Y-284814D01*
X334797Y-284184D01*
X335345Y-283764D01*
X335972Y-283659D01*
X336599Y-283764D01*
X337147Y-284184D01*
X337617Y-284814D01*
X337930Y-285549D01*
X338087Y-286389D01*
Y-287229D01*
X337930Y-288069D01*
X337617Y-288804D01*
X337147Y-289434D01*
X336599Y-289854D01*
X335972Y-289959D01*
G01X342272Y-290169D02*
X342115Y-290064D01*
Y-289854D01*
X342272Y-289749D01*
X342429Y-289854D01*
Y-290064D01*
X342272Y-290169D01*
G01X347084Y-284709D02*
X347554Y-284079D01*
X348102Y-283764D01*
X348729Y-283659D01*
X349512Y-283869D01*
X350060Y-284394D01*
X350217Y-285024D01*
X350139Y-285654D01*
X349825Y-286179D01*
X348259Y-287229D01*
X347554Y-287964D01*
X347084Y-289014D01*
X346927Y-289959D01*
X350217D01*
G01X354872D02*
Y-283659D01*
X353932Y-284919D01*
G01Y-289959D02*
X355812D01*
G01X361172D02*
Y-283659D01*
X360232Y-284919D01*
G01Y-289959D02*
X362112D01*
G01X367315Y-291114D02*
X367629Y-289749D01*
G01X371422Y-283659D02*
X372519Y-289959D01*
X373772Y-283659D01*
X375025Y-289959D01*
X376122Y-283659D01*
G01X381639Y-289959D02*
X378505D01*
Y-283659D01*
X381639D01*
G01X380385Y-286704D02*
X378505D01*
G01X384570Y-289959D02*
Y-283659D01*
X388174Y-289959D01*
Y-283659D01*
G01X391027Y-289959D02*
Y-283659D01*
G01X394317D02*
Y-289959D01*
G01Y-286809D02*
X391027D01*
G01X397249Y-283659D02*
Y-288174D01*
X397562Y-289119D01*
X398189Y-289749D01*
X398972Y-289959D01*
X399755Y-289749D01*
X400382Y-289119D01*
X400695Y-288174D01*
Y-283659D01*
G01X403314Y-289959D02*
X405272Y-283659D01*
X407230Y-289959D01*
G01X406525Y-287754D02*
X404019D01*
G01X416384Y-284709D02*
X416854Y-284079D01*
X417402Y-283764D01*
X418029Y-283659D01*
X418812Y-283869D01*
X419360Y-284394D01*
X419517Y-285024D01*
X419439Y-285654D01*
X419125Y-286179D01*
X417559Y-287229D01*
X416854Y-287964D01*
X416384Y-289014D01*
X416227Y-289959D01*
X419517D01*
G01X422370D02*
Y-283659D01*
X425974Y-289959D01*
Y-283659D01*
G01X428749Y-289959D02*
Y-283659D01*
X430315D01*
X430942Y-283974D01*
X431412Y-284394D01*
X431804Y-285024D01*
X432117Y-285759D01*
X432195Y-286809D01*
X432117Y-287859D01*
X431804Y-288594D01*
X431412Y-289224D01*
X430942Y-289644D01*
X430315Y-289959D01*
X428749D01*
G01X441505D02*
Y-283659D01*
X443464D01*
X444090Y-283974D01*
X444482Y-284394D01*
X444639Y-285234D01*
X444482Y-286074D01*
X444012Y-286599D01*
X443464Y-286914D01*
X441505D01*
G01X443464D02*
X444639Y-289959D01*
G01X447649D02*
Y-283659D01*
X449215D01*
X449842Y-283974D01*
X450312Y-284394D01*
X450704Y-285024D01*
X451017Y-285759D01*
X451095Y-286809D01*
X451017Y-287859D01*
X450704Y-288594D01*
X450312Y-289224D01*
X449842Y-289644D01*
X449215Y-289959D01*
X447649D01*
G01X455672Y-290169D02*
X455515Y-290064D01*
Y-289854D01*
X455672Y-289749D01*
X455829Y-289854D01*
Y-290064D01*
X455672Y-290169D01*
G01X351972Y-279259D02*
X349452Y-278842D01*
X347247Y-277176D01*
X345357Y-274676D01*
X344097Y-271759D01*
X343467Y-268426D01*
Y-265092D01*
X344097Y-261759D01*
X345357Y-258842D01*
X347247Y-256343D01*
X349452Y-254676D01*
X351972Y-254259D01*
X354492Y-254676D01*
X356697Y-256343D01*
X358587Y-258842D01*
X359847Y-261759D01*
X360477Y-265092D01*
Y-268426D01*
X359847Y-271759D01*
X358587Y-274676D01*
X356697Y-277176D01*
X354492Y-278842D01*
X351972Y-279259D01*
G01X354492Y-272592D02*
X358272Y-279259D01*
G01X371817Y-262593D02*
Y-274259D01*
X373077Y-277176D01*
X374967Y-278842D01*
X377172Y-279259D01*
X379377Y-278842D01*
X381267Y-277176D01*
X382527Y-274259D01*
G01Y-279259D02*
Y-262593D01*
G01X408042Y-279259D02*
Y-262593D01*
G01Y-265509D02*
X406782Y-263843D01*
X404892Y-263009D01*
X402687Y-262593D01*
X400482Y-263426D01*
X398592Y-265092D01*
X397332Y-267593D01*
X396702Y-270926D01*
X397332Y-274259D01*
X398592Y-276760D01*
X400482Y-278426D01*
X402687Y-279259D01*
X404892Y-278842D01*
X406782Y-277593D01*
X408042Y-275926D01*
G01X422217Y-279259D02*
Y-262593D01*
G01Y-266759D02*
X423477Y-264676D01*
X425367Y-263009D01*
X427887Y-262593D01*
X430092Y-263009D01*
X431982Y-264676D01*
X432927Y-267593D01*
Y-279259D01*
G01X452772Y-254259D02*
Y-279259D01*
G01X448362Y-262593D02*
X457182D01*
G01X483642Y-279259D02*
Y-262593D01*
G01Y-265509D02*
X482382Y-263843D01*
X480492Y-263009D01*
X478287Y-262593D01*
X476082Y-263426D01*
X474192Y-265092D01*
X472932Y-267593D01*
X472302Y-270926D01*
X472932Y-274259D01*
X474192Y-276760D01*
X476082Y-278426D01*
X478287Y-279259D01*
X480492Y-278842D01*
X482382Y-277593D01*
X483642Y-275926D01*
G01X536722Y-291959D02*
Y-283959D01*
X539322Y-290626D01*
X541922Y-283959D01*
Y-291959D01*
G01X544822D02*
X547322Y-283959D01*
X549822Y-291959D01*
G01X548922Y-289159D02*
X545722D01*
G01X553222Y-290893D02*
X554022Y-291559D01*
X554922Y-291959D01*
X555722D01*
X556522Y-291559D01*
X557122Y-290893D01*
X557422Y-289959D01*
X557222Y-289026D01*
X556722Y-288226D01*
X555822Y-287692D01*
X554622Y-287426D01*
X553922Y-286892D01*
X553622Y-285959D01*
X553822Y-285026D01*
X554322Y-284359D01*
X555022Y-283959D01*
X555722D01*
X556422Y-284226D01*
X557022Y-284892D01*
G01X561122Y-291959D02*
Y-283959D01*
G01X564922D02*
X561122Y-288893D01*
G01X565522Y-291959D02*
X562822Y-286626D01*
G01X570022Y-289292D02*
X572622D01*
G01X580122Y-287692D02*
X580522Y-287292D01*
X580822Y-286626D01*
X581022Y-285692D01*
X580822Y-284892D01*
X580422Y-284359D01*
X579722Y-283959D01*
X577022D01*
Y-291959D01*
X580322D01*
X581022Y-291426D01*
X581422Y-290626D01*
X581622Y-289692D01*
X581422Y-288759D01*
X580822Y-287959D01*
X580122Y-287692D01*
X577022D01*
G01X587322Y-291959D02*
X586522Y-291826D01*
X585822Y-291292D01*
X585222Y-290492D01*
X584822Y-289559D01*
X584622Y-288492D01*
Y-287426D01*
X584822Y-286359D01*
X585222Y-285426D01*
X585822Y-284626D01*
X586522Y-284092D01*
X587322Y-283959D01*
X588122Y-284092D01*
X588822Y-284626D01*
X589422Y-285426D01*
X589822Y-286359D01*
X590022Y-287426D01*
Y-288492D01*
X589822Y-289559D01*
X589422Y-290492D01*
X588822Y-291292D01*
X588122Y-291826D01*
X587322Y-291959D01*
G01X595322Y-283959D02*
Y-291959D01*
G01X593022Y-283959D02*
X597622D01*
G01X523322Y-258959D02*
Y-266959D01*
X527322D01*
G01X535122D02*
Y-261626D01*
G01Y-262559D02*
X534722Y-262026D01*
X534122Y-261759D01*
X533422Y-261626D01*
X532722Y-261892D01*
X532122Y-262426D01*
X531722Y-263226D01*
X531522Y-264292D01*
X531722Y-265359D01*
X532122Y-266159D01*
X532722Y-266692D01*
X533422Y-266959D01*
X534122Y-266826D01*
X534722Y-266426D01*
X535122Y-265893D01*
G01X539222Y-269359D02*
X539822Y-269626D01*
X540622Y-269359D01*
X541122Y-268826D01*
X541522Y-268159D01*
X542122Y-266026D01*
X543422Y-261626D01*
G01X540222D02*
X542122Y-266026D01*
G01X547822Y-263359D02*
X551022D01*
X550722Y-262426D01*
X550222Y-261892D01*
X549522Y-261626D01*
X548822Y-261759D01*
X548222Y-262159D01*
X547822Y-263092D01*
X547622Y-263893D01*
Y-264692D01*
X547822Y-265492D01*
X548322Y-266292D01*
X548922Y-266826D01*
X549622Y-266959D01*
X550322Y-266692D01*
X551022Y-265893D01*
G01X555922Y-266959D02*
Y-261626D01*
G01Y-262692D02*
X556422Y-262159D01*
X556922Y-261759D01*
X557622Y-261626D01*
X558122Y-261759D01*
X558722Y-262159D01*
G01X542022Y-316959D02*
Y-308959D01*
X546622Y-316959D01*
Y-308959D01*
G01X552322Y-311626D02*
Y-316959D01*
G01Y-309492D02*
X552122Y-309359D01*
Y-309092D01*
X552322Y-308959D01*
X552522Y-309092D01*
Y-309359D01*
X552322Y-309492D01*
G01X558622Y-316959D02*
Y-311626D01*
G01Y-312959D02*
X559022Y-312292D01*
X559622Y-311759D01*
X560422Y-311626D01*
X561122Y-311759D01*
X561722Y-312292D01*
X562022Y-313226D01*
Y-316959D01*
G01X570122D02*
Y-311626D01*
G01Y-312559D02*
X569722Y-312026D01*
X569122Y-311759D01*
X568422Y-311626D01*
X567722Y-311892D01*
X567122Y-312426D01*
X566722Y-313226D01*
X566522Y-314292D01*
X566722Y-315359D01*
X567122Y-316159D01*
X567722Y-316692D01*
X568422Y-316959D01*
X569122Y-316826D01*
X569722Y-316426D01*
X570122Y-315893D01*
G01X649922Y-310292D02*
X650522Y-309492D01*
X651222Y-309092D01*
X652022Y-308959D01*
X653022Y-309226D01*
X653722Y-309892D01*
X653922Y-310692D01*
X653822Y-311493D01*
X653422Y-312159D01*
X651422Y-313492D01*
X650522Y-314426D01*
X649922Y-315759D01*
X649722Y-316959D01*
X653922D01*
G01X659822Y-308959D02*
X659022Y-309226D01*
X658422Y-309892D01*
X658022Y-310692D01*
X657722Y-311759D01*
X657622Y-312959D01*
X657722Y-314159D01*
X658022Y-315226D01*
X658422Y-316026D01*
X659022Y-316692D01*
X659822Y-316959D01*
X660622Y-316692D01*
X661222Y-316026D01*
X661622Y-315226D01*
X661922Y-314159D01*
X662022Y-312959D01*
X661922Y-311759D01*
X661622Y-310692D01*
X661222Y-309892D01*
X660622Y-309226D01*
X659822Y-308959D01*
G01X665922Y-310292D02*
X666522Y-309492D01*
X667222Y-309092D01*
X668022Y-308959D01*
X669022Y-309226D01*
X669722Y-309892D01*
X669922Y-310692D01*
X669822Y-311493D01*
X669422Y-312159D01*
X667422Y-313492D01*
X666522Y-314426D01*
X665922Y-315759D01*
X665722Y-316959D01*
X669922D01*
G01X673922Y-310292D02*
X674522Y-309492D01*
X675222Y-309092D01*
X676022Y-308959D01*
X677022Y-309226D01*
X677722Y-309892D01*
X677922Y-310692D01*
X677822Y-311493D01*
X677422Y-312159D01*
X675422Y-313492D01*
X674522Y-314426D01*
X673922Y-315759D01*
X673722Y-316959D01*
X677922D01*
G01X682022Y-317226D02*
X685622Y-308959D01*
G01X691822Y-316959D02*
Y-308959D01*
X690622Y-310559D01*
G01Y-316959D02*
X693022D01*
G01X697922Y-310292D02*
X698522Y-309492D01*
X699222Y-309092D01*
X700022Y-308959D01*
X701022Y-309226D01*
X701722Y-309892D01*
X701922Y-310692D01*
X701822Y-311493D01*
X701422Y-312159D01*
X699422Y-313492D01*
X698522Y-314426D01*
X697922Y-315759D01*
X697722Y-316959D01*
X701922D01*
G01X706022Y-317226D02*
X709622Y-308959D01*
G01X715822D02*
X715022Y-309226D01*
X714422Y-309892D01*
X714022Y-310692D01*
X713722Y-311759D01*
X713622Y-312959D01*
X713722Y-314159D01*
X714022Y-315226D01*
X714422Y-316026D01*
X715022Y-316692D01*
X715822Y-316959D01*
X716622Y-316692D01*
X717222Y-316026D01*
X717622Y-315226D01*
X717922Y-314159D01*
X718022Y-312959D01*
X717922Y-311759D01*
X717622Y-310692D01*
X717222Y-309892D01*
X716622Y-309226D01*
X715822Y-308959D01*
G01X722122Y-316026D02*
X722822Y-316692D01*
X723622Y-316959D01*
X724422Y-316692D01*
X725122Y-315893D01*
X725622Y-314692D01*
X725822Y-313492D01*
Y-312026D01*
X725622Y-310826D01*
X725122Y-309759D01*
X724522Y-309226D01*
X723822Y-308959D01*
X723022Y-309226D01*
X722422Y-309759D01*
X722022Y-310559D01*
X721822Y-311626D01*
X722022Y-312559D01*
X722522Y-313492D01*
X723122Y-314026D01*
X723822Y-314159D01*
X724622Y-313893D01*
X725222Y-313226D01*
X725822Y-312026D01*
G01X649622Y-291959D02*
Y-283959D01*
X651622D01*
X652422Y-284359D01*
X653022Y-284892D01*
X653522Y-285692D01*
X653922Y-286626D01*
X654022Y-287959D01*
X653922Y-289292D01*
X653522Y-290226D01*
X653022Y-291026D01*
X652422Y-291559D01*
X651622Y-291959D01*
X649622D01*
G01X657322D02*
X659822Y-283959D01*
X662322Y-291959D01*
G01X661422Y-289159D02*
X658222D01*
G01X667822Y-283959D02*
X667022Y-284226D01*
X666422Y-284892D01*
X666022Y-285692D01*
X665722Y-286759D01*
X665622Y-287959D01*
X665722Y-289159D01*
X666022Y-290226D01*
X666422Y-291026D01*
X667022Y-291692D01*
X667822Y-291959D01*
X668622Y-291692D01*
X669222Y-291026D01*
X669622Y-290226D01*
X669922Y-289159D01*
X670022Y-287959D01*
X669922Y-286759D01*
X669622Y-285692D01*
X669222Y-284892D01*
X668622Y-284226D01*
X667822Y-283959D01*
G01X673922Y-291959D02*
Y-283959D01*
X677722D01*
G01X676322Y-287826D02*
X673922D01*
G01X683822Y-283959D02*
X683022Y-284226D01*
X682422Y-284892D01*
X682022Y-285692D01*
X681722Y-286759D01*
X681622Y-287959D01*
X681722Y-289159D01*
X682022Y-290226D01*
X682422Y-291026D01*
X683022Y-291692D01*
X683822Y-291959D01*
X684622Y-291692D01*
X685222Y-291026D01*
X685622Y-290226D01*
X685922Y-289159D01*
X686022Y-287959D01*
X685922Y-286759D01*
X685622Y-285692D01*
X685222Y-284892D01*
X684622Y-284226D01*
X683822Y-283959D01*
G01X691822D02*
Y-291959D01*
G01X689522Y-283959D02*
X694122D01*
G01X697922Y-291959D02*
Y-283959D01*
X701722D01*
G01X700322Y-287826D02*
X697922D01*
G01X708622Y-287692D02*
X709022Y-287292D01*
X709322Y-286626D01*
X709522Y-285692D01*
X709322Y-284892D01*
X708922Y-284359D01*
X708222Y-283959D01*
X705522D01*
Y-291959D01*
X708822D01*
X709522Y-291426D01*
X709922Y-290626D01*
X710122Y-289692D01*
X709922Y-288759D01*
X709322Y-287959D01*
X708622Y-287692D01*
X705522D01*
G01X713922Y-288626D02*
X714622Y-287692D01*
X715222Y-287159D01*
X716022Y-286892D01*
X716722Y-287159D01*
X717222Y-287692D01*
X717622Y-288492D01*
X717722Y-289426D01*
X717622Y-290226D01*
X717222Y-291026D01*
X716622Y-291692D01*
X715922Y-291959D01*
X715122Y-291692D01*
X714422Y-290893D01*
X714022Y-289692D01*
X713922Y-288359D01*
X714122Y-286626D01*
X714422Y-285692D01*
X714922Y-284759D01*
X715622Y-284092D01*
X716322Y-283959D01*
X717022Y-284226D01*
X717522Y-284892D01*
G01X721622Y-291959D02*
Y-283959D01*
X723622D01*
X724422Y-284359D01*
X725022Y-284892D01*
X725522Y-285692D01*
X725922Y-286626D01*
X726022Y-287959D01*
X725922Y-289292D01*
X725522Y-290226D01*
X725022Y-291026D01*
X724422Y-291559D01*
X723622Y-291959D01*
X721622D01*
G01X731822Y-283959D02*
X731022Y-284226D01*
X730422Y-284892D01*
X730022Y-285692D01*
X729722Y-286759D01*
X729622Y-287959D01*
X729722Y-289159D01*
X730022Y-290226D01*
X730422Y-291026D01*
X731022Y-291692D01*
X731822Y-291959D01*
X732622Y-291692D01*
X733222Y-291026D01*
X733622Y-290226D01*
X733922Y-289159D01*
X734022Y-287959D01*
X733922Y-286759D01*
X733622Y-285692D01*
X733222Y-284892D01*
X732622Y-284226D01*
X731822Y-283959D01*
G01X649862Y-270000D02*
Y-263700D01*
X652838D01*
G01X651742Y-266745D02*
X649862D01*
G01X657650Y-263700D02*
X657023Y-263910D01*
X656553Y-264435D01*
X656240Y-265065D01*
X656005Y-265905D01*
X655927Y-266850D01*
X656005Y-267795D01*
X656240Y-268635D01*
X656553Y-269265D01*
X657023Y-269790D01*
X657650Y-270000D01*
X658277Y-269790D01*
X658747Y-269265D01*
X659060Y-268635D01*
X659295Y-267795D01*
X659373Y-266850D01*
X659295Y-265905D01*
X659060Y-265065D01*
X658747Y-264435D01*
X658277Y-263910D01*
X657650Y-263700D01*
G01X663950D02*
Y-270000D01*
G01X662148Y-263700D02*
X665752D01*
G01X667900Y-272100D02*
X672600D01*
G01X674983Y-270000D02*
Y-263700D01*
X676863D01*
X677490Y-264015D01*
X677960Y-264750D01*
X678117Y-265590D01*
X677960Y-266430D01*
X677568Y-267060D01*
X676863Y-267375D01*
X674983D01*
G01X684573Y-264225D02*
X684103Y-263910D01*
X683555Y-263700D01*
X682928D01*
X682223Y-264015D01*
X681675Y-264540D01*
X681283Y-265170D01*
X680970Y-266220D01*
X680892Y-267165D01*
X681048Y-268110D01*
X681283Y-268740D01*
X681753Y-269370D01*
X682302Y-269790D01*
X682850Y-270000D01*
X683398D01*
X683947Y-269790D01*
X684417Y-269475D01*
X684808Y-269055D01*
G01X689777Y-266640D02*
X690090Y-266325D01*
X690325Y-265800D01*
X690482Y-265065D01*
X690325Y-264435D01*
X690012Y-264015D01*
X689463Y-263700D01*
X687348D01*
Y-270000D01*
X689933D01*
X690482Y-269580D01*
X690795Y-268950D01*
X690952Y-268215D01*
X690795Y-267480D01*
X690325Y-266850D01*
X689777Y-266640D01*
X687348D01*
G01X693100Y-272100D02*
X697800D01*
G01X700262Y-270000D02*
Y-263700D01*
X703238D01*
G01X702142Y-266745D02*
X700262D01*
G01X706092Y-270000D02*
X708050Y-263700D01*
X710008Y-270000D01*
G01X709303Y-267795D02*
X706797D01*
G01X712548Y-270000D02*
Y-263700D01*
X716152Y-270000D01*
Y-263700D01*
G01X718300Y-272100D02*
X723000D01*
G01X727577Y-266640D02*
X727890Y-266325D01*
X728125Y-265800D01*
X728282Y-265065D01*
X728125Y-264435D01*
X727812Y-264015D01*
X727263Y-263700D01*
X725148D01*
Y-270000D01*
X727733D01*
X728282Y-269580D01*
X728595Y-268950D01*
X728752Y-268215D01*
X728595Y-267480D01*
X728125Y-266850D01*
X727577Y-266640D01*
X725148D01*
G01X733250Y-270000D02*
X732623Y-269895D01*
X732075Y-269475D01*
X731605Y-268845D01*
X731292Y-268110D01*
X731135Y-267270D01*
Y-266430D01*
X731292Y-265590D01*
X731605Y-264855D01*
X732075Y-264225D01*
X732623Y-263805D01*
X733250Y-263700D01*
X733877Y-263805D01*
X734425Y-264225D01*
X734895Y-264855D01*
X735208Y-265590D01*
X735365Y-266430D01*
Y-267270D01*
X735208Y-268110D01*
X734895Y-268845D01*
X734425Y-269475D01*
X733877Y-269895D01*
X733250Y-270000D01*
G01X737592D02*
X739550Y-263700D01*
X741508Y-270000D01*
G01X740803Y-267795D02*
X738297D01*
G01X744283Y-270000D02*
Y-263700D01*
X746242D01*
X746868Y-264015D01*
X747260Y-264435D01*
X747417Y-265275D01*
X747260Y-266115D01*
X746790Y-266640D01*
X746242Y-266955D01*
X744283D01*
G01X746242D02*
X747417Y-270000D01*
G01X750427D02*
Y-263700D01*
X751993D01*
X752620Y-264015D01*
X753090Y-264435D01*
X753482Y-265065D01*
X753795Y-265800D01*
X753873Y-266850D01*
X753795Y-267900D01*
X753482Y-268635D01*
X753090Y-269265D01*
X752620Y-269685D01*
X751993Y-270000D01*
X750427D01*
G01X756100Y-272100D02*
X760800D01*
G01X762713Y-270000D02*
Y-263700D01*
X764750Y-268950D01*
X766787Y-263700D01*
Y-270000D01*
G01X769483D02*
Y-263700D01*
X771363D01*
X771990Y-264015D01*
X772460Y-264750D01*
X772617Y-265590D01*
X772460Y-266430D01*
X772068Y-267060D01*
X771363Y-267375D01*
X769483D01*
G01X775627Y-269055D02*
X776097Y-269580D01*
X776645Y-269895D01*
X777350Y-270000D01*
X778055Y-269790D01*
X778603Y-269370D01*
X778995Y-268635D01*
X779073Y-267795D01*
X778917Y-266955D01*
X778525Y-266430D01*
X777977Y-266010D01*
X777428Y-265905D01*
X776880Y-266010D01*
X776175Y-266430D01*
X776410Y-263700D01*
X778525D01*
G01X783650D02*
X783023Y-263910D01*
X782553Y-264435D01*
X782240Y-265065D01*
X782005Y-265905D01*
X781927Y-266850D01*
X782005Y-267795D01*
X782240Y-268635D01*
X782553Y-269265D01*
X783023Y-269790D01*
X783650Y-270000D01*
X784277Y-269790D01*
X784747Y-269265D01*
X785060Y-268635D01*
X785295Y-267795D01*
X785373Y-266850D01*
X785295Y-265905D01*
X785060Y-265065D01*
X784747Y-264435D01*
X784277Y-263910D01*
X783650Y-263700D01*
G01X790890Y-270000D02*
Y-263700D01*
X787992Y-268215D01*
X791908D01*
G01X796250Y-270000D02*
X796798Y-269895D01*
X797425Y-269580D01*
X797817Y-269055D01*
X797973Y-268320D01*
X797817Y-267585D01*
X797347Y-266955D01*
X796642Y-266640D01*
X795858D01*
X795388Y-266430D01*
X794997Y-265905D01*
X794840Y-265170D01*
X795075Y-264435D01*
X795623Y-263910D01*
X796250Y-263700D01*
X796877Y-263910D01*
X797425Y-264435D01*
X797660Y-265170D01*
X797503Y-265905D01*
X797112Y-266430D01*
X796642Y-266640D01*
X795858D01*
X795153Y-266955D01*
X794683Y-267585D01*
X794527Y-268320D01*
X794683Y-269055D01*
X795075Y-269580D01*
X795702Y-269895D01*
X796250Y-270000D01*
G01X738322Y-319959D02*
Y-311959D01*
X737122Y-313559D01*
G01Y-319959D02*
X739522D01*
G01X744422Y-316626D02*
X745122Y-315692D01*
X745722Y-315159D01*
X746522Y-314892D01*
X747222Y-315159D01*
X747722Y-315692D01*
X748122Y-316492D01*
X748222Y-317426D01*
X748122Y-318226D01*
X747722Y-319026D01*
X747122Y-319692D01*
X746422Y-319959D01*
X745622Y-319692D01*
X744922Y-318893D01*
X744522Y-317692D01*
X744422Y-316359D01*
X744622Y-314626D01*
X744922Y-313692D01*
X745422Y-312759D01*
X746122Y-312092D01*
X746822Y-311959D01*
X747522Y-312226D01*
X748022Y-312892D01*
G01X754322Y-320226D02*
X754122Y-320092D01*
Y-319826D01*
X754322Y-319692D01*
X754522Y-319826D01*
Y-320092D01*
X754322Y-320226D01*
G01X760422Y-316626D02*
X761122Y-315692D01*
X761722Y-315159D01*
X762522Y-314892D01*
X763222Y-315159D01*
X763722Y-315692D01*
X764122Y-316492D01*
X764222Y-317426D01*
X764122Y-318226D01*
X763722Y-319026D01*
X763122Y-319692D01*
X762422Y-319959D01*
X761622Y-319692D01*
X760922Y-318893D01*
X760522Y-317692D01*
X760422Y-316359D01*
X760622Y-314626D01*
X760922Y-313692D01*
X761422Y-312759D01*
X762122Y-312092D01*
X762822Y-311959D01*
X763522Y-312226D01*
X764022Y-312892D01*
G01X783322Y-319959D02*
Y-311959D01*
X782122Y-313559D01*
G01Y-319959D02*
X784522D01*
G01X791122D02*
X791322Y-318226D01*
X791622Y-316759D01*
X792022Y-315426D01*
X792522Y-313959D01*
X793322Y-311959D01*
X789322D01*
G01X799322Y-320226D02*
X799122Y-320092D01*
Y-319826D01*
X799322Y-319692D01*
X799522Y-319826D01*
Y-320092D01*
X799322Y-320226D01*
G01X805422Y-313292D02*
X806022Y-312492D01*
X806722Y-312092D01*
X807522Y-311959D01*
X808522Y-312226D01*
X809222Y-312892D01*
X809422Y-313692D01*
X809322Y-314493D01*
X808922Y-315159D01*
X806922Y-316492D01*
X806022Y-317426D01*
X805422Y-318759D01*
X805222Y-319959D01*
X809422D01*
G01X803122Y-294959D02*
Y-286959D01*
X805122D01*
X805922Y-287359D01*
X806522Y-287892D01*
X807022Y-288692D01*
X807422Y-289626D01*
X807522Y-290959D01*
X807422Y-292292D01*
X807022Y-293226D01*
X806522Y-294026D01*
X805922Y-294559D01*
X805122Y-294959D01*
X803122D01*
G54D24*
X13584Y241516D03*
Y968288D03*
X46478Y323444D03*
X46978Y1050216D03*
X137275Y241516D03*
Y971437D03*
X155775Y323444D03*
Y1050216D03*
G54D33*
X11000Y256747D03*
X10500Y983483D03*
X41123Y292675D03*
X45123D03*
X49000Y292683D03*
X37061Y292675D03*
X42123Y1019447D03*
X46123D03*
X50000Y1019483D03*
X38061Y1019447D03*
X59500Y292711D03*
X63500D03*
X68061D03*
X60500Y1019483D03*
X76561D03*
X64500D03*
X68561D03*
X131500Y256747D03*
X147500D03*
X130500Y986668D03*
X146500D03*
X147500Y1019483D03*
X171000Y292711D03*
X152420Y292675D03*
X156420D03*
X160500Y292711D03*
X148500Y292675D03*
X165500Y1019483D03*
X151420Y1019447D03*
X155420D03*
X159500Y1019483D03*
X187000Y292711D03*
X175000D03*
X179000D03*
X185500Y1019483D03*
X173500D03*
X177500D03*
G54D15*
X34252Y64606D03*
Y56732D03*
Y48858D03*
X26378Y64606D03*
Y56732D03*
X34252Y88228D03*
Y80354D03*
Y72480D03*
X26378Y88228D03*
Y80354D03*
Y72480D03*
X34252Y103976D03*
Y96102D03*
X26378Y103976D03*
Y96102D03*
X34252Y412244D03*
Y435866D03*
Y427992D03*
Y420118D03*
X26378Y435866D03*
Y427992D03*
Y420118D03*
X34252Y451614D03*
Y443740D03*
X26378Y451614D03*
Y443740D03*
X34252Y467362D03*
Y459488D03*
X26378Y467362D03*
Y459488D03*
X34252Y775630D03*
Y799252D03*
Y791378D03*
Y783504D03*
X26378Y799252D03*
Y791378D03*
Y783504D03*
X34252Y822874D03*
Y815000D03*
Y807126D03*
X26378Y822874D03*
Y815000D03*
Y807126D03*
X34252Y830748D03*
X26378D03*
X34252Y1146890D03*
Y1139016D03*
X26378Y1146890D03*
X34252Y1170512D03*
Y1162638D03*
Y1154764D03*
X26378Y1170512D03*
Y1162638D03*
Y1154764D03*
X34252Y1194134D03*
Y1186260D03*
Y1178386D03*
X26378Y1194134D03*
Y1186260D03*
Y1178386D03*
X169291Y48858D03*
Y56732D03*
Y64606D03*
Y72480D03*
Y80354D03*
Y88228D03*
Y96102D03*
Y103976D03*
Y412244D03*
Y420118D03*
Y427992D03*
Y435866D03*
Y443740D03*
Y451614D03*
Y459488D03*
Y467362D03*
Y775630D03*
Y783504D03*
Y791378D03*
Y799252D03*
Y807126D03*
Y815000D03*
Y822874D03*
Y830748D03*
Y1139016D03*
Y1146890D03*
Y1154764D03*
Y1162638D03*
Y1170512D03*
Y1178386D03*
Y1186260D03*
Y1194134D03*
X177165Y48858D03*
Y56732D03*
Y64606D03*
Y72480D03*
Y80354D03*
Y88228D03*
Y96102D03*
Y412244D03*
Y420118D03*
Y427992D03*
Y435866D03*
Y443740D03*
Y451614D03*
Y459488D03*
Y775630D03*
Y783504D03*
Y791378D03*
Y799252D03*
Y807126D03*
Y815000D03*
Y822874D03*
Y1139016D03*
Y1146890D03*
Y1154764D03*
Y1162638D03*
Y1170512D03*
Y1178386D03*
Y1186260D03*
G54D42*
X49824Y309468D03*
X50324Y1036240D03*
X159121Y309468D03*
Y1036240D03*
G54D43*
X72561Y292803D03*
Y289653D03*
X77061D03*
Y292803D03*
G54D34*
X23016Y257500D03*
Y984500D03*
G54D16*
X26378Y48858D03*
Y412244D03*
Y775630D03*
Y1139016D03*
X177165Y103976D03*
Y467362D03*
Y830748D03*
Y1194134D03*
G54D25*
X17127Y236988D03*
Y233839D03*
Y227540D03*
X29331D03*
Y230689D03*
X17127Y963760D03*
Y960611D03*
Y954312D03*
X29331D03*
Y957461D03*
X50021Y315767D03*
Y318916D03*
X50521Y1045688D03*
Y1042539D03*
X62225Y309468D03*
Y312617D03*
Y318916D03*
X62725Y1036240D03*
Y1039389D03*
Y1045688D03*
X140818Y236988D03*
Y233839D03*
Y227540D03*
Y963760D03*
Y957461D03*
Y966909D03*
X153022Y227540D03*
Y230689D03*
X171522Y309468D03*
Y312617D03*
X159318Y315767D03*
X171522Y318916D03*
X159318D03*
X153022Y957461D03*
Y960610D03*
X171522Y1036240D03*
Y1039389D03*
Y1045688D03*
X159318D03*
Y1042539D03*
G54D26*
X29528Y236988D03*
Y963760D03*
X153219Y236988D03*
Y966909D03*
G54D44*
X71075Y501500D03*
X67925D03*
X71075Y497000D03*
X67925D03*
X71075Y519500D03*
X67925D03*
X71075Y524000D03*
X67925D03*
X71075Y515000D03*
X67925D03*
X71075Y510500D03*
X67925D03*
X71075Y506000D03*
X67925D03*
X71075Y528500D03*
X67925D03*
X162575Y498500D03*
X159425D03*
X162575Y503000D03*
X159425D03*
X162575Y507500D03*
X159425D03*
X162575Y512000D03*
X159425D03*
X162575Y516500D03*
X159425D03*
X162575Y525500D03*
X159425D03*
X162575Y521000D03*
X159425D03*
X162575Y530000D03*
X159425D03*
G54D17*
X15458Y162928D03*
X13837Y887582D03*
X42230Y162928D03*
X40609Y887582D03*
X156214Y169628D03*
X160114Y893200D03*
X182986Y169628D03*
X186886Y893200D03*
G54D35*
X25983Y257500D03*
Y984500D03*
G54D45*
X63000Y1237000D03*
X120000Y267500D03*
X187900Y675200D03*
G54D18*
X18244Y180800D03*
X29844D03*
X18195Y190606D03*
X29795D03*
X18251Y200306D03*
X29851D03*
X16232Y916362D03*
X27832D03*
X16232Y905862D03*
X27832D03*
X16232Y926862D03*
X27832D03*
X69600Y358228D03*
X58000D03*
X69600Y348228D03*
X58000D03*
X69600Y368228D03*
X58000D03*
X71874Y1081751D03*
X60274D03*
X71874Y1071251D03*
X60274D03*
X71874Y1092251D03*
X60274D03*
X125900Y1077600D03*
Y1088100D03*
Y1098600D03*
X132600Y358028D03*
X144200D03*
X132600Y348028D03*
X144200D03*
X132600Y368028D03*
X144200D03*
X137500Y1077600D03*
Y1088100D03*
Y1098600D03*
X170200Y187500D03*
Y197500D03*
X170100Y207400D03*
X167700Y912000D03*
Y932772D03*
Y922500D03*
X181800Y187500D03*
Y197500D03*
X181700Y207400D03*
X179300Y912000D03*
Y932772D03*
Y922500D03*
G54D27*
X27502Y268287D03*
Y265728D03*
Y263169D03*
Y995059D03*
Y992500D03*
Y989941D03*
X35080Y268287D03*
Y263169D03*
X44272Y278169D03*
Y283287D03*
X51850Y278169D03*
Y280728D03*
Y283287D03*
X35080Y995059D03*
Y989941D03*
X44772Y1004941D03*
Y1010059D03*
X52350Y1004941D03*
Y1007500D03*
Y1010059D03*
X158771Y268287D03*
Y263169D03*
X151193Y268287D03*
Y265728D03*
Y263169D03*
X153569Y278169D03*
Y283287D03*
X161147Y278169D03*
Y280728D03*
Y283287D03*
X153569Y1004941D03*
Y1010059D03*
X161147Y1004941D03*
Y1007500D03*
Y1010059D03*
X158771Y998208D03*
Y993090D03*
X151193Y998208D03*
Y995649D03*
Y993090D03*
G54D36*
X21185Y295736D03*
Y321720D03*
X21685Y1022508D03*
Y1048492D03*
X58167Y239736D03*
Y265720D03*
X59367Y963908D03*
Y989892D03*
X130482Y295736D03*
Y321720D03*
Y1022508D03*
Y1048492D03*
X182958Y237136D03*
Y263120D03*
X183800Y962708D03*
Y988692D03*
G54D19*
X18351Y208906D03*
X25351D03*
X16462Y935899D03*
X23462D03*
X69500Y339300D03*
X62500D03*
X71649Y1062686D03*
X64649D03*
X134000Y339000D03*
X141000D03*
X131000Y1069000D03*
X138000D03*
X172177Y941600D03*
X179400Y215900D03*
X172400D03*
X179177Y941600D03*
G54D28*
X15000Y271043D03*
Y998543D03*
X66561Y276685D03*
X67061Y1003457D03*
X136482Y269771D03*
Y999692D03*
X175858Y276685D03*
Y1003457D03*
G54D37*
X21685Y342406D03*
Y369178D03*
Y1069178D03*
Y1095950D03*
X181858Y342406D03*
Y369178D03*
X183800Y1069214D03*
Y1095986D03*
G54D46*
X82992Y17126D03*
X87992D03*
X92992D03*
X97992D03*
G54D38*
X42717Y597091D03*
X101772Y180748D03*
Y928779D03*
X160827Y597091D03*
G54D29*
X12047Y263957D03*
X17953D03*
Y271043D03*
X12047D03*
Y991457D03*
X17953D03*
Y998543D03*
X12047D03*
X69514Y283771D03*
X63608D03*
Y276685D03*
X69514D03*
X70014Y1010543D03*
X64108D03*
Y1003457D03*
X70014D03*
X133529Y262685D03*
X139435D03*
Y269771D03*
X133529D03*
Y992606D03*
X139435D03*
Y999692D03*
X133529D03*
X178811Y283771D03*
X172905D03*
Y276685D03*
X178811D03*
Y1010543D03*
X172905D03*
Y1003457D03*
X178811D03*
G54D47*
X101772Y1243747D03*
G54D48*
X116772Y19685D03*
G54D39*
X17100Y1233000D03*
X22900D03*
G54D49*
X176000Y1231100D03*
Y1236900D03*
M02*
